FILE_TYPE = MACRO_DRAWING;
SET COLOR_WIRE YELLOW;
SET COLOR_PROP MONO;
SET COLOR_DOT WHITE;
SET COLOR_ARC YELLOW;
SET COLOR_BODY GREEN;
SET COLOR_NOTE MONO;
SET PROP_DISPLAY VALUE;
SET PAGE_NUMBER P47;
FORCEADD OFFPAGE..3
(1600 5250);
FORCEPROP 2 LAST $XR1 48 
J 0
(1904 5250);
DISPLAY 0.638298 (1904 5250);
PAINT MONO (1904 5250);
FORCEPROP 2 LAST $XR0 25 
J 0
(1814 5250);
DISPLAY 0.638298 (1814 5250);
PAINT MONO (1814 5250);
FORCEPROP 2 LAST CDS_LIB mstr_standard
J 0
(1600 5250);
DISPLAY 0.787234 (1600 5250);
PAINT MONO (1600 5250);
DISPLAY INVISIBLE (1600 5250);
FORCEPROP 1 LAST OFFPAGE TRUE
J 0
(1925 5125);
DISPLAY 0.936170 (1925 5125);
PAINT GREEN (1925 5125);
DISPLAY INVISIBLE (1925 5125);
FORCEPROP 1 LAST COMMENT_BODY TRUE
J 0
(1550 5150);
DISPLAY 0.936170 (1550 5150);
PAINT GREEN (1550 5150);
DISPLAY INVISIBLE (1550 5150);
FORCEPROP 2 LAST PATH I1
J 0
(1800 5325);
DISPLAY 0.787234 (1800 5325);
PAINT MONO (1800 5325);
DISPLAY INVISIBLE (1800 5325);
FORCEADD TAP..6
R 2
(700 4900);
FORCEPROP 3 LASTPIN (650 4900) SIG_NAME M_C_DQS_DP<14>
J 0
(660 4910);
DISPLAY 0.659574 (660 4910);
PAINT MONO (660 4910);
DISPLAY INVISIBLE (660 4910);
FORCEPROP 1 LASTPIN (650 4900) BN 14
J 2
(700 4910);
DISPLAY 0.617021 (700 4910);
PAINT PINK (700 4910);
FORCEPROP 2 LAST CDS_LIB mstr_standard
J 0
(700 4900);
DISPLAY 0.787234 (700 4900);
PAINT MONO (700 4900);
DISPLAY INVISIBLE (700 4900);
FORCEPROP 1 LAST BODY_TYPE PLUMBING
J 2
(700 4850);
DISPLAY 1.234043 (700 4850);
PAINT GREEN (700 4850);
DISPLAY INVISIBLE (700 4850);
FORCEPROP 1 LAST HDL_TAP TRUE
J 2
(375 4775);
DISPLAY 1.234043 (375 4775);
PAINT GREEN (375 4775);
DISPLAY INVISIBLE (375 4775);
FORCEPROP 1 LAST PATH I10
J 2
(700 4900);
DISPLAY 0.936170 (700 4900);
PAINT GREEN (700 4900);
DISPLAY INVISIBLE (700 4900);
FORCEADD TAP..6
R 2
(-1700 1900);
FORCEPROP 3 LASTPIN (-1750 1900) SIG_NAME M_C_DQ<9>
J 0
(-1740 1910);
DISPLAY 0.659574 (-1740 1910);
PAINT MONO (-1740 1910);
DISPLAY INVISIBLE (-1740 1910);
FORCEPROP 1 LASTPIN (-1750 1900) BN 9
J 2
(-1700 1910);
DISPLAY 0.617021 (-1700 1910);
PAINT PINK (-1700 1910);
FORCEPROP 2 LAST CDS_LIB mstr_standard
J 2
(-1700 1900);
DISPLAY 0.787234 (-1700 1900);
PAINT MONO (-1700 1900);
DISPLAY INVISIBLE (-1700 1900);
FORCEPROP 1 LAST BODY_TYPE PLUMBING
J 2
(-1700 1850);
DISPLAY 1.234043 (-1700 1850);
PAINT GREEN (-1700 1850);
DISPLAY INVISIBLE (-1700 1850);
FORCEPROP 1 LAST HDL_TAP TRUE
J 2
(-2025 1775);
DISPLAY 1.234043 (-2025 1775);
PAINT GREEN (-2025 1775);
DISPLAY INVISIBLE (-2025 1775);
FORCEPROP 1 LAST PATH I100
J 2
(-1700 1900);
DISPLAY 0.936170 (-1700 1900);
PAINT GREEN (-1700 1900);
DISPLAY INVISIBLE (-1700 1900);
FORCEADD TAP..6
R 2
(-1700 2000);
FORCEPROP 3 LASTPIN (-1750 2000) SIG_NAME M_C_DQ<11>
J 0
(-1740 2010);
DISPLAY 0.659574 (-1740 2010);
PAINT MONO (-1740 2010);
DISPLAY INVISIBLE (-1740 2010);
FORCEPROP 1 LASTPIN (-1750 2000) BN 11
J 2
(-1700 2010);
DISPLAY 0.617021 (-1700 2010);
PAINT PINK (-1700 2010);
FORCEPROP 2 LAST CDS_LIB mstr_standard
J 2
(-1700 2000);
DISPLAY 0.787234 (-1700 2000);
PAINT MONO (-1700 2000);
DISPLAY INVISIBLE (-1700 2000);
FORCEPROP 1 LAST BODY_TYPE PLUMBING
J 2
(-1700 1950);
DISPLAY 1.234043 (-1700 1950);
PAINT GREEN (-1700 1950);
DISPLAY INVISIBLE (-1700 1950);
FORCEPROP 1 LAST HDL_TAP TRUE
J 2
(-2025 1875);
DISPLAY 1.234043 (-2025 1875);
PAINT GREEN (-2025 1875);
DISPLAY INVISIBLE (-2025 1875);
FORCEPROP 1 LAST PATH I101
J 2
(-1700 2000);
DISPLAY 0.936170 (-1700 2000);
PAINT GREEN (-1700 2000);
DISPLAY INVISIBLE (-1700 2000);
FORCEADD TAP..6
R 2
(-1700 1950);
FORCEPROP 3 LASTPIN (-1750 1950) SIG_NAME M_C_DQ<8>
J 0
(-1740 1960);
DISPLAY 0.659574 (-1740 1960);
PAINT MONO (-1740 1960);
DISPLAY INVISIBLE (-1740 1960);
FORCEPROP 1 LASTPIN (-1750 1950) BN 8
J 2
(-1700 1960);
DISPLAY 0.617021 (-1700 1960);
PAINT PINK (-1700 1960);
FORCEPROP 2 LAST CDS_LIB mstr_standard
J 2
(-1700 1950);
DISPLAY 0.787234 (-1700 1950);
PAINT MONO (-1700 1950);
DISPLAY INVISIBLE (-1700 1950);
FORCEPROP 1 LAST BODY_TYPE PLUMBING
J 2
(-1700 1900);
DISPLAY 1.234043 (-1700 1900);
PAINT GREEN (-1700 1900);
DISPLAY INVISIBLE (-1700 1900);
FORCEPROP 1 LAST HDL_TAP TRUE
J 2
(-2025 1825);
DISPLAY 1.234043 (-2025 1825);
PAINT GREEN (-2025 1825);
DISPLAY INVISIBLE (-2025 1825);
FORCEPROP 1 LAST PATH I102
J 2
(-1700 1950);
DISPLAY 0.936170 (-1700 1950);
PAINT GREEN (-1700 1950);
DISPLAY INVISIBLE (-1700 1950);
FORCEADD TAP..6
R 2
(-1700 1750);
FORCEPROP 3 LASTPIN (-1750 1750) SIG_NAME M_C_DQ<4>
J 0
(-1740 1760);
DISPLAY 0.659574 (-1740 1760);
PAINT MONO (-1740 1760);
DISPLAY INVISIBLE (-1740 1760);
FORCEPROP 1 LASTPIN (-1750 1750) BN 4
J 2
(-1700 1760);
DISPLAY 0.617021 (-1700 1760);
PAINT PINK (-1700 1760);
FORCEPROP 2 LAST CDS_LIB mstr_standard
J 2
(-1700 1750);
DISPLAY 0.787234 (-1700 1750);
PAINT MONO (-1700 1750);
DISPLAY INVISIBLE (-1700 1750);
FORCEPROP 1 LAST BODY_TYPE PLUMBING
J 2
(-1700 1700);
DISPLAY 1.234043 (-1700 1700);
PAINT GREEN (-1700 1700);
DISPLAY INVISIBLE (-1700 1700);
FORCEPROP 1 LAST HDL_TAP TRUE
J 2
(-2025 1625);
DISPLAY 1.234043 (-2025 1625);
PAINT GREEN (-2025 1625);
DISPLAY INVISIBLE (-2025 1625);
FORCEPROP 1 LAST PATH I103
J 2
(-1700 1750);
DISPLAY 0.936170 (-1700 1750);
PAINT GREEN (-1700 1750);
DISPLAY INVISIBLE (-1700 1750);
FORCEADD TAP..6
R 2
(-1700 1800);
FORCEPROP 3 LASTPIN (-1750 1800) SIG_NAME M_C_DQ<7>
J 0
(-1740 1810);
DISPLAY 0.659574 (-1740 1810);
PAINT MONO (-1740 1810);
DISPLAY INVISIBLE (-1740 1810);
FORCEPROP 1 LASTPIN (-1750 1800) BN 7
J 2
(-1700 1810);
DISPLAY 0.617021 (-1700 1810);
PAINT PINK (-1700 1810);
FORCEPROP 2 LAST CDS_LIB mstr_standard
J 2
(-1700 1800);
DISPLAY 0.787234 (-1700 1800);
PAINT MONO (-1700 1800);
DISPLAY INVISIBLE (-1700 1800);
FORCEPROP 1 LAST BODY_TYPE PLUMBING
J 2
(-1700 1750);
DISPLAY 1.234043 (-1700 1750);
PAINT GREEN (-1700 1750);
DISPLAY INVISIBLE (-1700 1750);
FORCEPROP 1 LAST HDL_TAP TRUE
J 2
(-2025 1675);
DISPLAY 1.234043 (-2025 1675);
PAINT GREEN (-2025 1675);
DISPLAY INVISIBLE (-2025 1675);
FORCEPROP 1 LAST PATH I104
J 2
(-1700 1800);
DISPLAY 0.936170 (-1700 1800);
PAINT GREEN (-1700 1800);
DISPLAY INVISIBLE (-1700 1800);
FORCEADD TAP..6
R 2
(-1700 1850);
FORCEPROP 3 LASTPIN (-1750 1850) SIG_NAME M_C_DQ<6>
J 0
(-1740 1860);
DISPLAY 0.659574 (-1740 1860);
PAINT MONO (-1740 1860);
DISPLAY INVISIBLE (-1740 1860);
FORCEPROP 1 LASTPIN (-1750 1850) BN 6
J 2
(-1700 1860);
DISPLAY 0.617021 (-1700 1860);
PAINT PINK (-1700 1860);
FORCEPROP 2 LAST CDS_LIB mstr_standard
J 2
(-1700 1850);
DISPLAY 0.787234 (-1700 1850);
PAINT MONO (-1700 1850);
DISPLAY INVISIBLE (-1700 1850);
FORCEPROP 1 LAST BODY_TYPE PLUMBING
J 2
(-1700 1800);
DISPLAY 1.234043 (-1700 1800);
PAINT GREEN (-1700 1800);
DISPLAY INVISIBLE (-1700 1800);
FORCEPROP 1 LAST HDL_TAP TRUE
J 2
(-2025 1725);
DISPLAY 1.234043 (-2025 1725);
PAINT GREEN (-2025 1725);
DISPLAY INVISIBLE (-2025 1725);
FORCEPROP 1 LAST PATH I105
J 2
(-1700 1850);
DISPLAY 0.936170 (-1700 1850);
PAINT GREEN (-1700 1850);
DISPLAY INVISIBLE (-1700 1850);
FORCEADD TAP..6
R 2
(-1700 1700);
FORCEPROP 3 LASTPIN (-1750 1700) SIG_NAME M_C_DQ<5>
J 0
(-1740 1710);
DISPLAY 0.659574 (-1740 1710);
PAINT MONO (-1740 1710);
DISPLAY INVISIBLE (-1740 1710);
FORCEPROP 1 LASTPIN (-1750 1700) BN 5
J 2
(-1700 1710);
DISPLAY 0.617021 (-1700 1710);
PAINT PINK (-1700 1710);
FORCEPROP 2 LAST CDS_LIB mstr_standard
J 2
(-1700 1700);
DISPLAY 0.787234 (-1700 1700);
PAINT MONO (-1700 1700);
DISPLAY INVISIBLE (-1700 1700);
FORCEPROP 1 LAST BODY_TYPE PLUMBING
J 2
(-1700 1650);
DISPLAY 1.234043 (-1700 1650);
PAINT GREEN (-1700 1650);
DISPLAY INVISIBLE (-1700 1650);
FORCEPROP 1 LAST HDL_TAP TRUE
J 2
(-2025 1575);
DISPLAY 1.234043 (-2025 1575);
PAINT GREEN (-2025 1575);
DISPLAY INVISIBLE (-2025 1575);
FORCEPROP 1 LAST PATH I106
J 2
(-1700 1700);
DISPLAY 0.936170 (-1700 1700);
PAINT GREEN (-1700 1700);
DISPLAY INVISIBLE (-1700 1700);
FORCEADD TAP..6
R 2
(-1700 1650);
FORCEPROP 3 LASTPIN (-1750 1650) SIG_NAME M_C_DQ<2>
J 0
(-1740 1660);
DISPLAY 0.659574 (-1740 1660);
PAINT MONO (-1740 1660);
DISPLAY INVISIBLE (-1740 1660);
FORCEPROP 1 LASTPIN (-1750 1650) BN 2
J 2
(-1700 1660);
DISPLAY 0.617021 (-1700 1660);
PAINT PINK (-1700 1660);
FORCEPROP 2 LAST CDS_LIB mstr_standard
J 2
(-1700 1650);
DISPLAY 0.787234 (-1700 1650);
PAINT MONO (-1700 1650);
DISPLAY INVISIBLE (-1700 1650);
FORCEPROP 1 LAST BODY_TYPE PLUMBING
J 2
(-1700 1600);
DISPLAY 1.234043 (-1700 1600);
PAINT GREEN (-1700 1600);
DISPLAY INVISIBLE (-1700 1600);
FORCEPROP 1 LAST HDL_TAP TRUE
J 2
(-2025 1525);
DISPLAY 1.234043 (-2025 1525);
PAINT GREEN (-2025 1525);
DISPLAY INVISIBLE (-2025 1525);
FORCEPROP 1 LAST PATH I107
J 2
(-1700 1650);
DISPLAY 0.936170 (-1700 1650);
PAINT GREEN (-1700 1650);
DISPLAY INVISIBLE (-1700 1650);
FORCEADD TAP..6
R 2
(-1700 1550);
FORCEPROP 3 LASTPIN (-1750 1550) SIG_NAME M_C_DQ<0>
J 0
(-1740 1560);
DISPLAY 0.659574 (-1740 1560);
PAINT MONO (-1740 1560);
DISPLAY INVISIBLE (-1740 1560);
FORCEPROP 1 LASTPIN (-1750 1550) BN 0
J 2
(-1700 1560);
DISPLAY 0.617021 (-1700 1560);
PAINT PINK (-1700 1560);
FORCEPROP 2 LAST CDS_LIB mstr_standard
J 2
(-1700 1550);
DISPLAY 0.787234 (-1700 1550);
PAINT MONO (-1700 1550);
DISPLAY INVISIBLE (-1700 1550);
FORCEPROP 1 LAST BODY_TYPE PLUMBING
J 2
(-1700 1500);
DISPLAY 1.234043 (-1700 1500);
PAINT GREEN (-1700 1500);
DISPLAY INVISIBLE (-1700 1500);
FORCEPROP 1 LAST HDL_TAP TRUE
J 2
(-2025 1425);
DISPLAY 1.234043 (-2025 1425);
PAINT GREEN (-2025 1425);
DISPLAY INVISIBLE (-2025 1425);
FORCEPROP 1 LAST PATH I108
J 2
(-1700 1550);
DISPLAY 0.936170 (-1700 1550);
PAINT GREEN (-1700 1550);
DISPLAY INVISIBLE (-1700 1550);
FORCEADD TAP..6
R 2
(-1700 1600);
FORCEPROP 3 LASTPIN (-1750 1600) SIG_NAME M_C_DQ<3>
J 0
(-1740 1610);
DISPLAY 0.659574 (-1740 1610);
PAINT MONO (-1740 1610);
DISPLAY INVISIBLE (-1740 1610);
FORCEPROP 1 LASTPIN (-1750 1600) BN 3
J 2
(-1700 1610);
DISPLAY 0.617021 (-1700 1610);
PAINT PINK (-1700 1610);
FORCEPROP 2 LAST CDS_LIB mstr_standard
J 2
(-1700 1600);
DISPLAY 0.787234 (-1700 1600);
PAINT MONO (-1700 1600);
DISPLAY INVISIBLE (-1700 1600);
FORCEPROP 1 LAST BODY_TYPE PLUMBING
J 2
(-1700 1550);
DISPLAY 1.234043 (-1700 1550);
PAINT GREEN (-1700 1550);
DISPLAY INVISIBLE (-1700 1550);
FORCEPROP 1 LAST HDL_TAP TRUE
J 2
(-2025 1475);
DISPLAY 1.234043 (-2025 1475);
PAINT GREEN (-2025 1475);
DISPLAY INVISIBLE (-2025 1475);
FORCEPROP 1 LAST PATH I109
J 2
(-1700 1600);
DISPLAY 0.936170 (-1700 1600);
PAINT GREEN (-1700 1600);
DISPLAY INVISIBLE (-1700 1600);
FORCEADD TAP..6
R 2
(-1700 1500);
FORCEPROP 3 LASTPIN (-1750 1500) SIG_NAME M_C_DQ<1>
J 0
(-1740 1510);
DISPLAY 0.659574 (-1740 1510);
PAINT MONO (-1740 1510);
DISPLAY INVISIBLE (-1740 1510);
FORCEPROP 1 LASTPIN (-1750 1500) BN 1
J 2
(-1700 1510);
DISPLAY 0.617021 (-1700 1510);
PAINT PINK (-1700 1510);
FORCEPROP 2 LAST CDS_LIB mstr_standard
J 2
(-1700 1500);
DISPLAY 0.787234 (-1700 1500);
PAINT MONO (-1700 1500);
DISPLAY INVISIBLE (-1700 1500);
FORCEPROP 1 LAST BODY_TYPE PLUMBING
J 2
(-1700 1450);
DISPLAY 1.234043 (-1700 1450);
PAINT GREEN (-1700 1450);
DISPLAY INVISIBLE (-1700 1450);
FORCEPROP 1 LAST HDL_TAP TRUE
J 2
(-2025 1375);
DISPLAY 1.234043 (-2025 1375);
PAINT GREEN (-2025 1375);
DISPLAY INVISIBLE (-2025 1375);
FORCEPROP 1 LAST PATH I110
J 2
(-1700 1500);
DISPLAY 0.936170 (-1700 1500);
PAINT GREEN (-1700 1500);
DISPLAY INVISIBLE (-1700 1500);
FORCEADD SCONN288_H44441004..1
(-2450 3000);
FORCEPROP 1 LAST PART_NUMBER H44441-004
J 0
(-2900 1000);
DISPLAY 0.617021 (-2900 1000);
PAINT BLUE (-2900 1000);
FORCEPROP 2 LASTPIN (-2950 1500) $PN 146
J 2
(-2960 1510);
DISPLAY 0.617021 (-2960 1510);
PAINT ORANGE (-2960 1510);
FORCEPROP 2 LASTPIN (-2950 1850) $PN 284
J 2
(-2960 1860);
DISPLAY 0.617021 (-2960 1860);
PAINT ORANGE (-2960 1860);
FORCEPROP 2 LASTPIN (-2950 1650) $PN 285
J 2
(-2960 1660);
DISPLAY 0.617021 (-2960 1660);
PAINT ORANGE (-2960 1660);
FORCEPROP 2 LASTPIN (-2950 1600) $PN 141
J 2
(-2960 1610);
DISPLAY 0.617021 (-2960 1610);
PAINT ORANGE (-2960 1610);
FORCEPROP 2 LASTPIN (-2950 1200) $PN 230
J 2
(-2960 1210);
DISPLAY 0.617021 (-2960 1210);
PAINT ORANGE (-2960 1210);
FORCEPROP 2 LASTPIN (-2950 1800) $PN 238
J 2
(-2960 1810);
DISPLAY 0.617021 (-2960 1810);
PAINT ORANGE (-2960 1810);
FORCEPROP 2 LASTPIN (-2950 1750) $PN 140
J 2
(-2960 1760);
DISPLAY 0.617021 (-2960 1760);
PAINT ORANGE (-2960 1760);
FORCEPROP 2 LASTPIN (-2950 1700) $PN 139
J 2
(-2960 1710);
DISPLAY 0.617021 (-2960 1710);
PAINT ORANGE (-2960 1710);
FORCEPROP 2 LASTPIN (-2950 3150) $PN 237
J 2
(-2960 3160);
DISPLAY 0.617021 (-2960 3160);
PAINT ORANGE (-2960 3160);
FORCEPROP 2 LASTPIN (-2950 3100) $PN 93
J 2
(-2960 3110);
DISPLAY 0.617021 (-2960 3110);
PAINT ORANGE (-2960 3110);
FORCEPROP 2 LASTPIN (-2950 3050) $PN 89
J 2
(-2960 3060);
DISPLAY 0.617021 (-2960 3060);
PAINT ORANGE (-2960 3060);
FORCEPROP 2 LASTPIN (-2950 3000) $PN 84
J 2
(-2960 3010);
DISPLAY 0.617021 (-2960 3010);
PAINT ORANGE (-2960 3010);
FORCEPROP 2 LASTPIN (-2950 1400) $PN 144
J 2
(-2960 1410);
DISPLAY 0.617021 (-2960 1410);
PAINT ORANGE (-2960 1410);
FORCEPROP 2 LASTPIN (-2950 1350) $PN 227
J 2
(-2960 1360);
DISPLAY 0.617021 (-2960 1360);
PAINT ORANGE (-2960 1360);
FORCEPROP 2 LASTPIN (-2950 1300) $PN 205
J 2
(-2960 1310);
DISPLAY 0.617021 (-2960 1310);
PAINT ORANGE (-2960 1310);
FORCEPROP 2 LASTPIN (-2950 2100) $PN 58
J 2
(-2960 2110);
DISPLAY 0.617021 (-2960 2110);
PAINT ORANGE (-2960 2110);
FORCEPROP 2 LASTPIN (-2950 2150) $PN 222
J 2
(-2960 2160);
DISPLAY 0.617021 (-2960 2160);
PAINT ORANGE (-2960 2160);
FORCEPROP 2 LASTPIN (-2950 2750) $PN 91
J 2
(-2960 2760);
DISPLAY 0.617021 (-2960 2760);
PAINT ORANGE (-2960 2760);
FORCEPROP 2 LASTPIN (-2950 2700) $PN 87
J 2
(-2960 2710);
DISPLAY 0.617021 (-2960 2710);
PAINT ORANGE (-2960 2710);
FORCEPROP 2 LASTPIN (-2950 2050) $PN 78
J 2
(-2960 2060);
DISPLAY 0.617021 (-2960 2060);
PAINT ORANGE (-2960 2060);
FORCEPROP 2 LASTPIN (-1950 4650) $PN 280
J 0
(-1940 4660);
DISPLAY 0.617021 (-1940 4660);
PAINT ORANGE (-1940 4660);
FORCEPROP 2 LASTPIN (-1950 4600) $PN 135
J 0
(-1940 4610);
DISPLAY 0.617021 (-1940 4610);
PAINT ORANGE (-1940 4610);
FORCEPROP 2 LASTPIN (-1950 4550) $PN 273
J 0
(-1940 4560);
DISPLAY 0.617021 (-1940 4560);
PAINT ORANGE (-1940 4560);
FORCEPROP 2 LASTPIN (-1950 4500) $PN 128
J 0
(-1940 4510);
DISPLAY 0.617021 (-1940 4510);
PAINT ORANGE (-1940 4510);
FORCEPROP 2 LASTPIN (-1950 4450) $PN 282
J 0
(-1940 4460);
DISPLAY 0.617021 (-1940 4460);
PAINT ORANGE (-1940 4460);
FORCEPROP 2 LASTPIN (-1950 4400) $PN 137
J 0
(-1940 4410);
DISPLAY 0.617021 (-1940 4410);
PAINT ORANGE (-1940 4410);
FORCEPROP 2 LASTPIN (-1950 4350) $PN 275
J 0
(-1940 4360);
DISPLAY 0.617021 (-1940 4360);
PAINT ORANGE (-1940 4360);
FORCEPROP 2 LASTPIN (-1950 4300) $PN 130
J 0
(-1940 4310);
DISPLAY 0.617021 (-1940 4310);
PAINT ORANGE (-1940 4310);
FORCEPROP 2 LASTPIN (-1950 4250) $PN 269
J 0
(-1940 4260);
DISPLAY 0.617021 (-1940 4260);
PAINT ORANGE (-1940 4260);
FORCEPROP 2 LASTPIN (-1950 4200) $PN 124
J 0
(-1940 4210);
DISPLAY 0.617021 (-1940 4210);
PAINT ORANGE (-1940 4210);
FORCEPROP 2 LASTPIN (-1950 4150) $PN 262
J 0
(-1940 4160);
DISPLAY 0.617021 (-1940 4160);
PAINT ORANGE (-1940 4160);
FORCEPROP 2 LASTPIN (-1950 4100) $PN 117
J 0
(-1940 4110);
DISPLAY 0.617021 (-1940 4110);
PAINT ORANGE (-1940 4110);
FORCEPROP 2 LASTPIN (-1950 4050) $PN 271
J 0
(-1940 4060);
DISPLAY 0.617021 (-1940 4060);
PAINT ORANGE (-1940 4060);
FORCEPROP 2 LASTPIN (-1950 4000) $PN 126
J 0
(-1940 4010);
DISPLAY 0.617021 (-1940 4010);
PAINT ORANGE (-1940 4010);
FORCEPROP 2 LASTPIN (-1950 3950) $PN 264
J 0
(-1940 3960);
DISPLAY 0.617021 (-1940 3960);
PAINT ORANGE (-1940 3960);
FORCEPROP 2 LASTPIN (-1950 3900) $PN 119
J 0
(-1940 3910);
DISPLAY 0.617021 (-1940 3910);
PAINT ORANGE (-1940 3910);
FORCEPROP 2 LASTPIN (-1950 3850) $PN 258
J 0
(-1940 3860);
DISPLAY 0.617021 (-1940 3860);
PAINT ORANGE (-1940 3860);
FORCEPROP 2 LASTPIN (-1950 3750) $PN 251
J 0
(-1940 3760);
DISPLAY 0.617021 (-1940 3760);
PAINT ORANGE (-1940 3760);
FORCEPROP 2 LASTPIN (-1950 3700) $PN 106
J 0
(-1940 3710);
DISPLAY 0.617021 (-1940 3710);
PAINT ORANGE (-1940 3710);
FORCEPROP 2 LASTPIN (-1950 3650) $PN 260
J 0
(-1940 3660);
DISPLAY 0.617021 (-1940 3660);
PAINT ORANGE (-1940 3660);
FORCEPROP 2 LASTPIN (-1950 3600) $PN 115
J 0
(-1940 3610);
DISPLAY 0.617021 (-1940 3610);
PAINT ORANGE (-1940 3610);
FORCEPROP 2 LASTPIN (-1950 3550) $PN 253
J 0
(-1940 3560);
DISPLAY 0.617021 (-1940 3560);
PAINT ORANGE (-1940 3560);
FORCEPROP 2 LASTPIN (-1950 3500) $PN 108
J 0
(-1940 3510);
DISPLAY 0.617021 (-1940 3510);
PAINT ORANGE (-1940 3510);
FORCEPROP 2 LASTPIN (-1950 3450) $PN 247
J 0
(-1940 3460);
DISPLAY 0.617021 (-1940 3460);
PAINT ORANGE (-1940 3460);
FORCEPROP 2 LASTPIN (-1950 3400) $PN 102
J 0
(-1940 3410);
DISPLAY 0.617021 (-1940 3410);
PAINT ORANGE (-1940 3410);
FORCEPROP 2 LASTPIN (-1950 3350) $PN 240
J 0
(-1940 3360);
DISPLAY 0.617021 (-1940 3360);
PAINT ORANGE (-1940 3360);
FORCEPROP 2 LASTPIN (-1950 3300) $PN 95
J 0
(-1940 3310);
DISPLAY 0.617021 (-1940 3310);
PAINT ORANGE (-1940 3310);
FORCEPROP 2 LASTPIN (-1950 3250) $PN 249
J 0
(-1940 3260);
DISPLAY 0.617021 (-1940 3260);
PAINT ORANGE (-1940 3260);
FORCEPROP 2 LASTPIN (-1950 3200) $PN 104
J 0
(-1940 3210);
DISPLAY 0.617021 (-1940 3210);
PAINT ORANGE (-1940 3210);
FORCEPROP 2 LASTPIN (-1950 3150) $PN 242
J 0
(-1940 3160);
DISPLAY 0.617021 (-1940 3160);
PAINT ORANGE (-1940 3160);
FORCEPROP 2 LASTPIN (-1950 3100) $PN 97
J 0
(-1940 3110);
DISPLAY 0.617021 (-1940 3110);
PAINT ORANGE (-1940 3110);
FORCEPROP 2 LASTPIN (-1950 3050) $PN 188
J 0
(-1940 3060);
DISPLAY 0.617021 (-1940 3060);
PAINT ORANGE (-1940 3060);
FORCEPROP 2 LASTPIN (-1950 3000) $PN 43
J 0
(-1940 3010);
DISPLAY 0.617021 (-1940 3010);
PAINT ORANGE (-1940 3010);
FORCEPROP 2 LASTPIN (-1950 2950) $PN 181
J 0
(-1940 2960);
DISPLAY 0.617021 (-1940 2960);
PAINT ORANGE (-1940 2960);
FORCEPROP 2 LASTPIN (-1950 2900) $PN 36
J 0
(-1940 2910);
DISPLAY 0.617021 (-1940 2910);
PAINT ORANGE (-1940 2910);
FORCEPROP 2 LASTPIN (-1950 2850) $PN 190
J 0
(-1940 2860);
DISPLAY 0.617021 (-1940 2860);
PAINT ORANGE (-1940 2860);
FORCEPROP 2 LASTPIN (-1950 2800) $PN 45
J 0
(-1940 2810);
DISPLAY 0.617021 (-1940 2810);
PAINT ORANGE (-1940 2810);
FORCEPROP 2 LASTPIN (-1950 2750) $PN 183
J 0
(-1940 2760);
DISPLAY 0.617021 (-1940 2760);
PAINT ORANGE (-1940 2760);
FORCEPROP 2 LASTPIN (-1950 2700) $PN 38
J 0
(-1940 2710);
DISPLAY 0.617021 (-1940 2710);
PAINT ORANGE (-1940 2710);
FORCEPROP 2 LASTPIN (-1950 2650) $PN 177
J 0
(-1940 2660);
DISPLAY 0.617021 (-1940 2660);
PAINT ORANGE (-1940 2660);
FORCEPROP 2 LASTPIN (-1950 2600) $PN 32
J 0
(-1940 2610);
DISPLAY 0.617021 (-1940 2610);
PAINT ORANGE (-1940 2610);
FORCEPROP 2 LASTPIN (-1950 2550) $PN 170
J 0
(-1940 2560);
DISPLAY 0.617021 (-1940 2560);
PAINT ORANGE (-1940 2560);
FORCEPROP 2 LASTPIN (-1950 2500) $PN 25
J 0
(-1940 2510);
DISPLAY 0.617021 (-1940 2510);
PAINT ORANGE (-1940 2510);
FORCEPROP 2 LASTPIN (-1950 2450) $PN 179
J 0
(-1940 2460);
DISPLAY 0.617021 (-1940 2460);
PAINT ORANGE (-1940 2460);
FORCEPROP 2 LASTPIN (-1950 2400) $PN 34
J 0
(-1940 2410);
DISPLAY 0.617021 (-1940 2410);
PAINT ORANGE (-1940 2410);
FORCEPROP 2 LASTPIN (-1950 2350) $PN 172
J 0
(-1940 2360);
DISPLAY 0.617021 (-1940 2360);
PAINT ORANGE (-1940 2360);
FORCEPROP 2 LASTPIN (-1950 2300) $PN 27
J 0
(-1940 2310);
DISPLAY 0.617021 (-1940 2310);
PAINT ORANGE (-1940 2310);
FORCEPROP 2 LASTPIN (-1950 2250) $PN 166
J 0
(-1940 2260);
DISPLAY 0.617021 (-1940 2260);
PAINT ORANGE (-1940 2260);
FORCEPROP 2 LASTPIN (-1950 2200) $PN 21
J 0
(-1940 2210);
DISPLAY 0.617021 (-1940 2210);
PAINT ORANGE (-1940 2210);
FORCEPROP 2 LASTPIN (-1950 2150) $PN 159
J 0
(-1940 2160);
DISPLAY 0.617021 (-1940 2160);
PAINT ORANGE (-1940 2160);
FORCEPROP 2 LASTPIN (-1950 2100) $PN 14
J 0
(-1940 2110);
DISPLAY 0.617021 (-1940 2110);
PAINT ORANGE (-1940 2110);
FORCEPROP 2 LASTPIN (-1950 2050) $PN 168
J 0
(-1940 2060);
DISPLAY 0.617021 (-1940 2060);
PAINT ORANGE (-1940 2060);
FORCEPROP 2 LASTPIN (-1950 2000) $PN 23
J 0
(-1940 2010);
DISPLAY 0.617021 (-1940 2010);
PAINT ORANGE (-1940 2010);
FORCEPROP 2 LASTPIN (-1950 1950) $PN 161
J 0
(-1940 1960);
DISPLAY 0.617021 (-1940 1960);
PAINT ORANGE (-1940 1960);
FORCEPROP 2 LASTPIN (-1950 1900) $PN 16
J 0
(-1940 1910);
DISPLAY 0.617021 (-1940 1910);
PAINT ORANGE (-1940 1910);
FORCEPROP 2 LASTPIN (-1950 1850) $PN 155
J 0
(-1940 1860);
DISPLAY 0.617021 (-1940 1860);
PAINT ORANGE (-1940 1860);
FORCEPROP 2 LASTPIN (-1950 1800) $PN 10
J 0
(-1940 1810);
DISPLAY 0.617021 (-1940 1810);
PAINT ORANGE (-1940 1810);
FORCEPROP 2 LASTPIN (-1950 1750) $PN 148
J 0
(-1940 1760);
DISPLAY 0.617021 (-1940 1760);
PAINT ORANGE (-1940 1760);
FORCEPROP 2 LASTPIN (-1950 1700) $PN 3
J 0
(-1940 1710);
DISPLAY 0.617021 (-1940 1710);
PAINT ORANGE (-1940 1710);
FORCEPROP 2 LASTPIN (-1950 1650) $PN 157
J 0
(-1940 1660);
DISPLAY 0.617021 (-1940 1660);
PAINT ORANGE (-1940 1660);
FORCEPROP 2 LASTPIN (-1950 1600) $PN 12
J 0
(-1940 1610);
DISPLAY 0.617021 (-1940 1610);
PAINT ORANGE (-1940 1610);
FORCEPROP 2 LASTPIN (-1950 1550) $PN 150
J 0
(-1940 1560);
DISPLAY 0.617021 (-1940 1560);
PAINT ORANGE (-1940 1560);
FORCEPROP 2 LASTPIN (-1950 1500) $PN 5
J 0
(-1940 1510);
DISPLAY 0.617021 (-1940 1510);
PAINT ORANGE (-1940 1510);
FORCEPROP 2 LASTPIN (-2950 2900) $PN 203
J 2
(-2960 2910);
DISPLAY 0.617021 (-2960 2910);
PAINT ORANGE (-2960 2910);
FORCEPROP 2 LASTPIN (-2950 2850) $PN 60
J 2
(-2960 2860);
DISPLAY 0.617021 (-2960 2860);
PAINT ORANGE (-2960 2860);
FORCEPROP 2 LASTPIN (-2950 3450) $PN 218
J 2
(-2960 3460);
DISPLAY 0.617021 (-2960 3460);
PAINT ORANGE (-2960 3460);
FORCEPROP 2 LASTPIN (-2950 3400) $PN 219
J 2
(-2960 3410);
DISPLAY 0.617021 (-2960 3410);
PAINT ORANGE (-2960 3410);
FORCEPROP 2 LASTPIN (-2950 3350) $PN 74
J 2
(-2960 3360);
DISPLAY 0.617021 (-2960 3360);
PAINT ORANGE (-2960 3360);
FORCEPROP 2 LASTPIN (-2950 3300) $PN 75
J 2
(-2960 3310);
DISPLAY 0.617021 (-2960 3310);
PAINT ORANGE (-2960 3310);
FORCEPROP 2 LASTPIN (-2950 2600) $PN 199
J 2
(-2960 2610);
DISPLAY 0.617021 (-2960 2610);
PAINT ORANGE (-2960 2610);
FORCEPROP 2 LASTPIN (-2950 2550) $PN 54
J 2
(-2960 2560);
DISPLAY 0.617021 (-2960 2560);
PAINT ORANGE (-2960 2560);
FORCEPROP 2 LASTPIN (-2950 2500) $PN 192
J 2
(-2960 2510);
DISPLAY 0.617021 (-2960 2510);
PAINT ORANGE (-2960 2510);
FORCEPROP 2 LASTPIN (-2950 2450) $PN 47
J 2
(-2960 2460);
DISPLAY 0.617021 (-2960 2460);
PAINT ORANGE (-2960 2460);
FORCEPROP 2 LASTPIN (-2950 2400) $PN 201
J 2
(-2960 2410);
DISPLAY 0.617021 (-2960 2410);
PAINT ORANGE (-2960 2410);
FORCEPROP 2 LASTPIN (-2950 2350) $PN 56
J 2
(-2960 2360);
DISPLAY 0.617021 (-2960 2360);
PAINT ORANGE (-2960 2360);
FORCEPROP 2 LASTPIN (-2950 2300) $PN 194
J 2
(-2960 2310);
DISPLAY 0.617021 (-2960 2310);
PAINT ORANGE (-2960 2310);
FORCEPROP 2 LASTPIN (-2950 2250) $PN 49
J 2
(-2960 2260);
DISPLAY 0.617021 (-2960 2260);
PAINT ORANGE (-2960 2260);
FORCEPROP 2 LASTPIN (-2950 3200) $PN 235
J 2
(-2960 3210);
DISPLAY 0.617021 (-2960 3210);
PAINT ORANGE (-2960 3210);
FORCEPROP 2 LASTPIN (-2950 3600) $PN 207
J 2
(-2960 3610);
DISPLAY 0.617021 (-2960 3610);
PAINT ORANGE (-2960 3610);
FORCEPROP 2 LASTPIN (-2950 3550) $PN 63
J 2
(-2960 3560);
DISPLAY 0.617021 (-2960 3560);
PAINT ORANGE (-2960 3560);
FORCEPROP 2 LASTPIN (-2950 3700) $PN 224
J 2
(-2960 3710);
DISPLAY 0.617021 (-2960 3710);
PAINT ORANGE (-2960 3710);
FORCEPROP 2 LASTPIN (-2950 3650) $PN 81
J 2
(-2960 3660);
DISPLAY 0.617021 (-2960 3660);
PAINT ORANGE (-2960 3660);
FORCEPROP 2 LASTPIN (-2950 2000) $PN 208
J 2
(-2960 2010);
DISPLAY 0.617021 (-2960 2010);
PAINT ORANGE (-2960 2010);
FORCEPROP 2 LASTPIN (-2950 1950) $PN 62
J 2
(-2960 1960);
DISPLAY 0.617021 (-2960 1960);
PAINT ORANGE (-2960 1960);
FORCEPROP 2 LASTPIN (-2950 4650) $PN 234
J 2
(-2960 4660);
DISPLAY 0.617021 (-2960 4660);
PAINT ORANGE (-2960 4660);
FORCEPROP 2 LASTPIN (-2950 4600) $PN 82
J 2
(-2960 4610);
DISPLAY 0.617021 (-2960 4610);
PAINT ORANGE (-2960 4610);
FORCEPROP 2 LASTPIN (-2950 4550) $PN 86
J 2
(-2960 4560);
DISPLAY 0.617021 (-2960 4560);
PAINT ORANGE (-2960 4560);
FORCEPROP 2 LASTPIN (-2950 4500) $PN 228
J 2
(-2960 4510);
DISPLAY 0.617021 (-2960 4510);
PAINT ORANGE (-2960 4510);
FORCEPROP 2 LASTPIN (-2950 4450) $PN 232
J 2
(-2960 4460);
DISPLAY 0.617021 (-2960 4460);
PAINT ORANGE (-2960 4460);
FORCEPROP 2 LASTPIN (-2950 4350) $PN 210
J 2
(-2960 4360);
DISPLAY 0.617021 (-2960 4360);
PAINT ORANGE (-2960 4360);
FORCEPROP 2 LASTPIN (-2950 4300) $PN 225
J 2
(-2960 4310);
DISPLAY 0.617021 (-2960 4310);
PAINT ORANGE (-2960 4310);
FORCEPROP 2 LASTPIN (-2950 4250) $PN 66
J 2
(-2960 4260);
DISPLAY 0.617021 (-2960 4260);
PAINT ORANGE (-2960 4260);
FORCEPROP 2 LASTPIN (-2950 4200) $PN 68
J 2
(-2960 4210);
DISPLAY 0.617021 (-2960 4210);
PAINT ORANGE (-2960 4210);
FORCEPROP 2 LASTPIN (-2950 4150) $PN 211
J 2
(-2960 4160);
DISPLAY 0.617021 (-2960 4160);
PAINT ORANGE (-2960 4160);
FORCEPROP 2 LASTPIN (-2950 4100) $PN 69
J 2
(-2960 4110);
DISPLAY 0.617021 (-2960 4110);
PAINT ORANGE (-2960 4110);
FORCEPROP 2 LASTPIN (-2950 4000) $PN 214
J 2
(-2960 4010);
DISPLAY 0.617021 (-2960 4010);
PAINT ORANGE (-2960 4010);
FORCEPROP 2 LASTPIN (-2950 3950) $PN 71
J 2
(-2960 3960);
DISPLAY 0.617021 (-2960 3960);
PAINT ORANGE (-2960 3960);
FORCEPROP 2 LASTPIN (-2950 3900) $PN 216
J 2
(-2960 3910);
DISPLAY 0.617021 (-2960 3910);
PAINT ORANGE (-2960 3910);
FORCEPROP 2 LASTPIN (-2950 3850) $PN 72
J 2
(-2960 3860);
DISPLAY 0.617021 (-2960 3860);
PAINT ORANGE (-2960 3860);
FORCEPROP 2 LASTPIN (-2950 3800) $PN 79
J 2
(-2960 3810);
DISPLAY 0.617021 (-2960 3810);
PAINT ORANGE (-2960 3810);
FORCEPROP 2 LASTPIN (-1950 3800) $PN 113
J 0
(-1940 3810);
DISPLAY 0.617021 (-1940 3810);
PAINT ORANGE (-1940 3810);
FORCEPROP 2 LASTPIN (-2950 4050) $PN 213
J 2
(-2960 4060);
DISPLAY 0.617021 (-2960 4060);
PAINT ORANGE (-2960 4060);
FORCEPROP 1 LAST MATERIAL SCONN
J 0
(-2900 4850);
DISPLAY 0.617021 (-2900 4850);
PAINT SKYBLUE (-2900 4850);
FORCEPROP 1 LAST LOCATION J4G3
J 0
(-2900 4900);
DISPLAY 0.617021 (-2900 4900);
PAINT AQUA (-2900 4900);
FORCEPROP 2 LASTPIN (-2950 4400) $PN 65
J 2
(-2960 4410);
DISPLAY 0.617021 (-2960 4410);
PAINT ORANGE (-2960 4410);
FORCEPROP 1 LAST PACK_TYPE PIP
J 0
(-2900 4950);
PAINT SKYBLUE (-2900 4950);
DISPLAY INVISIBLE (-2900 4950);
FORCEPROP 2 LAST BOM_COST MEM
J 0
(-2450 3000);
PAINT ORANGE (-2450 3000);
DISPLAY INVISIBLE (-2450 3000);
FORCEPROP 2 LAST CDS_LIB mstr_sconn
J 0
(-2450 3000);
PAINT ORANGE (-2450 3000);
DISPLAY INVISIBLE (-2450 3000);
FORCEPROP 2 LAST SEC_TYPE PIP
J 0
(-2900 4950);
DISPLAY 1.021277 (-2900 4950);
PAINT ORANGE (-2900 4950);
DISPLAY INVISIBLE (-2900 4950);
FORCEPROP 2 LAST SEC 1
J 0
(-2900 4950);
DISPLAY 0.680851 (-2900 4950);
PAINT MONO (-2900 4950);
DISPLAY INVISIBLE (-2900 4950);
FORCEPROP 2 LAST CDS_LOCATION J4G3
J 0
(-2900 4900);
DISPLAY 0.617021 (-2900 4900);
PAINT AQUA (-2900 4900);
DISPLAY INVISIBLE (-2900 4900);
FORCEPROP 1 LAST PATH I111
J 0
(-2450 4850);
PAINT GREEN (-2450 4850);
DISPLAY INVISIBLE (-2450 4850);
FORCEPROP 2 LAST ROOM DDR4_CH_C
J 0
(-2450 3000);
PAINT ORANGE (-2450 3000);
DISPLAY INVISIBLE (-2450 3000);
FORCEADD TAP..6
(-3200 4650);
FORCEPROP 3 LASTPIN (-3150 4650) SIG_NAME M_C_MA<17>
J 0
(-3140 4660);
DISPLAY 0.659574 (-3140 4660);
PAINT MONO (-3140 4660);
DISPLAY INVISIBLE (-3140 4660);
FORCEPROP 1 LASTPIN (-3150 4650) BN 17
J 0
(-3200 4660);
DISPLAY 0.617021 (-3200 4660);
PAINT PINK (-3200 4660);
FORCEPROP 2 LAST CDS_LIB mstr_standard
J 0
(-3200 4650);
DISPLAY 0.787234 (-3200 4650);
PAINT MONO (-3200 4650);
DISPLAY INVISIBLE (-3200 4650);
FORCEPROP 1 LAST BODY_TYPE PLUMBING
J 0
(-3200 4600);
DISPLAY 1.234043 (-3200 4600);
PAINT GREEN (-3200 4600);
DISPLAY INVISIBLE (-3200 4600);
FORCEPROP 1 LAST HDL_TAP TRUE
J 0
(-2875 4525);
DISPLAY 1.234043 (-2875 4525);
PAINT GREEN (-2875 4525);
DISPLAY INVISIBLE (-2875 4525);
FORCEPROP 1 LAST PATH I112
J 0
(-3200 4650);
DISPLAY 0.936170 (-3200 4650);
PAINT GREEN (-3200 4650);
DISPLAY INVISIBLE (-3200 4650);
FORCEADD TAP..6
(-3200 4600);
FORCEPROP 3 LASTPIN (-3150 4600) SIG_NAME M_C_MA<16>
J 0
(-3140 4610);
DISPLAY 0.659574 (-3140 4610);
PAINT MONO (-3140 4610);
DISPLAY INVISIBLE (-3140 4610);
FORCEPROP 1 LASTPIN (-3150 4600) BN 16
J 0
(-3200 4610);
DISPLAY 0.617021 (-3200 4610);
PAINT PINK (-3200 4610);
FORCEPROP 2 LAST CDS_LIB mstr_standard
J 2
(-3200 4600);
DISPLAY 0.787234 (-3200 4600);
PAINT MONO (-3200 4600);
DISPLAY INVISIBLE (-3200 4600);
FORCEPROP 1 LAST BODY_TYPE PLUMBING
J 0
(-3200 4550);
DISPLAY 1.234043 (-3200 4550);
PAINT GREEN (-3200 4550);
DISPLAY INVISIBLE (-3200 4550);
FORCEPROP 1 LAST HDL_TAP TRUE
J 0
(-2875 4475);
DISPLAY 1.234043 (-2875 4475);
PAINT GREEN (-2875 4475);
DISPLAY INVISIBLE (-2875 4475);
FORCEPROP 1 LAST PATH I113
J 0
(-3200 4600);
DISPLAY 0.936170 (-3200 4600);
PAINT GREEN (-3200 4600);
DISPLAY INVISIBLE (-3200 4600);
FORCEADD TAP..6
(-3200 4550);
FORCEPROP 3 LASTPIN (-3150 4550) SIG_NAME M_C_MA<15>
J 0
(-3140 4560);
DISPLAY 0.659574 (-3140 4560);
PAINT MONO (-3140 4560);
DISPLAY INVISIBLE (-3140 4560);
FORCEPROP 1 LASTPIN (-3150 4550) BN 15
J 0
(-3200 4560);
DISPLAY 0.617021 (-3200 4560);
PAINT PINK (-3200 4560);
FORCEPROP 2 LAST CDS_LIB mstr_standard
J 2
(-3200 4550);
DISPLAY 0.787234 (-3200 4550);
PAINT MONO (-3200 4550);
DISPLAY INVISIBLE (-3200 4550);
FORCEPROP 1 LAST BODY_TYPE PLUMBING
J 0
(-3200 4500);
DISPLAY 1.234043 (-3200 4500);
PAINT GREEN (-3200 4500);
DISPLAY INVISIBLE (-3200 4500);
FORCEPROP 1 LAST HDL_TAP TRUE
J 0
(-2875 4425);
DISPLAY 1.234043 (-2875 4425);
PAINT GREEN (-2875 4425);
DISPLAY INVISIBLE (-2875 4425);
FORCEPROP 1 LAST PATH I114
J 0
(-3200 4550);
DISPLAY 0.936170 (-3200 4550);
PAINT GREEN (-3200 4550);
DISPLAY INVISIBLE (-3200 4550);
FORCEADD TAP..6
(-3200 4500);
FORCEPROP 3 LASTPIN (-3150 4500) SIG_NAME M_C_MA<14>
J 0
(-3140 4510);
DISPLAY 0.659574 (-3140 4510);
PAINT MONO (-3140 4510);
DISPLAY INVISIBLE (-3140 4510);
FORCEPROP 1 LASTPIN (-3150 4500) BN 14
J 0
(-3200 4510);
DISPLAY 0.617021 (-3200 4510);
PAINT PINK (-3200 4510);
FORCEPROP 2 LAST CDS_LIB mstr_standard
J 2
(-3200 4500);
DISPLAY 0.787234 (-3200 4500);
PAINT MONO (-3200 4500);
DISPLAY INVISIBLE (-3200 4500);
FORCEPROP 1 LAST BODY_TYPE PLUMBING
J 0
(-3200 4450);
DISPLAY 1.234043 (-3200 4450);
PAINT GREEN (-3200 4450);
DISPLAY INVISIBLE (-3200 4450);
FORCEPROP 1 LAST HDL_TAP TRUE
J 0
(-2875 4375);
DISPLAY 1.234043 (-2875 4375);
PAINT GREEN (-2875 4375);
DISPLAY INVISIBLE (-2875 4375);
FORCEPROP 1 LAST PATH I115
J 0
(-3200 4500);
DISPLAY 0.936170 (-3200 4500);
PAINT GREEN (-3200 4500);
DISPLAY INVISIBLE (-3200 4500);
FORCEADD TAP..6
(-3200 4450);
FORCEPROP 3 LASTPIN (-3150 4450) SIG_NAME M_C_MA<13>
J 0
(-3140 4460);
DISPLAY 0.659574 (-3140 4460);
PAINT MONO (-3140 4460);
DISPLAY INVISIBLE (-3140 4460);
FORCEPROP 1 LASTPIN (-3150 4450) BN 13
J 0
(-3200 4460);
DISPLAY 0.617021 (-3200 4460);
PAINT PINK (-3200 4460);
FORCEPROP 2 LAST CDS_LIB mstr_standard
J 2
(-3200 4450);
DISPLAY 0.787234 (-3200 4450);
PAINT MONO (-3200 4450);
DISPLAY INVISIBLE (-3200 4450);
FORCEPROP 1 LAST BODY_TYPE PLUMBING
J 0
(-3200 4400);
DISPLAY 1.234043 (-3200 4400);
PAINT GREEN (-3200 4400);
DISPLAY INVISIBLE (-3200 4400);
FORCEPROP 1 LAST HDL_TAP TRUE
J 0
(-2875 4325);
DISPLAY 1.234043 (-2875 4325);
PAINT GREEN (-2875 4325);
DISPLAY INVISIBLE (-2875 4325);
FORCEPROP 1 LAST PATH I116
J 0
(-3200 4450);
DISPLAY 0.936170 (-3200 4450);
PAINT GREEN (-3200 4450);
DISPLAY INVISIBLE (-3200 4450);
FORCEADD TAP..6
(-3200 4400);
FORCEPROP 3 LASTPIN (-3150 4400) SIG_NAME M_C_MA<12>
J 0
(-3140 4410);
DISPLAY 0.659574 (-3140 4410);
PAINT MONO (-3140 4410);
DISPLAY INVISIBLE (-3140 4410);
FORCEPROP 1 LASTPIN (-3150 4400) BN 12
J 0
(-3200 4410);
DISPLAY 0.617021 (-3200 4410);
PAINT PINK (-3200 4410);
FORCEPROP 2 LAST CDS_LIB mstr_standard
J 2
(-3200 4400);
DISPLAY 0.787234 (-3200 4400);
PAINT MONO (-3200 4400);
DISPLAY INVISIBLE (-3200 4400);
FORCEPROP 1 LAST BODY_TYPE PLUMBING
J 0
(-3200 4350);
DISPLAY 1.234043 (-3200 4350);
PAINT GREEN (-3200 4350);
DISPLAY INVISIBLE (-3200 4350);
FORCEPROP 1 LAST HDL_TAP TRUE
J 0
(-2875 4275);
DISPLAY 1.234043 (-2875 4275);
PAINT GREEN (-2875 4275);
DISPLAY INVISIBLE (-2875 4275);
FORCEPROP 1 LAST PATH I117
J 0
(-3200 4400);
DISPLAY 0.936170 (-3200 4400);
PAINT GREEN (-3200 4400);
DISPLAY INVISIBLE (-3200 4400);
FORCEADD TAP..6
(-3200 4350);
FORCEPROP 3 LASTPIN (-3150 4350) SIG_NAME M_C_MA<11>
J 0
(-3140 4360);
DISPLAY 0.659574 (-3140 4360);
PAINT MONO (-3140 4360);
DISPLAY INVISIBLE (-3140 4360);
FORCEPROP 1 LASTPIN (-3150 4350) BN 11
J 0
(-3200 4360);
DISPLAY 0.617021 (-3200 4360);
PAINT PINK (-3200 4360);
FORCEPROP 2 LAST CDS_LIB mstr_standard
J 2
(-3200 4350);
DISPLAY 0.787234 (-3200 4350);
PAINT MONO (-3200 4350);
DISPLAY INVISIBLE (-3200 4350);
FORCEPROP 1 LAST BODY_TYPE PLUMBING
J 0
(-3200 4300);
DISPLAY 1.234043 (-3200 4300);
PAINT GREEN (-3200 4300);
DISPLAY INVISIBLE (-3200 4300);
FORCEPROP 1 LAST HDL_TAP TRUE
J 0
(-2875 4225);
DISPLAY 1.234043 (-2875 4225);
PAINT GREEN (-2875 4225);
DISPLAY INVISIBLE (-2875 4225);
FORCEPROP 1 LAST PATH I118
J 0
(-3200 4350);
DISPLAY 0.936170 (-3200 4350);
PAINT GREEN (-3200 4350);
DISPLAY INVISIBLE (-3200 4350);
FORCEADD TAP..6
(-3200 4300);
FORCEPROP 3 LASTPIN (-3150 4300) SIG_NAME M_C_MA<10>
J 0
(-3140 4310);
DISPLAY 0.659574 (-3140 4310);
PAINT MONO (-3140 4310);
DISPLAY INVISIBLE (-3140 4310);
FORCEPROP 1 LASTPIN (-3150 4300) BN 10
J 0
(-3200 4310);
DISPLAY 0.617021 (-3200 4310);
PAINT PINK (-3200 4310);
FORCEPROP 2 LAST CDS_LIB mstr_standard
J 2
(-3200 4300);
DISPLAY 0.787234 (-3200 4300);
PAINT MONO (-3200 4300);
DISPLAY INVISIBLE (-3200 4300);
FORCEPROP 1 LAST BODY_TYPE PLUMBING
J 0
(-3200 4250);
DISPLAY 1.234043 (-3200 4250);
PAINT GREEN (-3200 4250);
DISPLAY INVISIBLE (-3200 4250);
FORCEPROP 1 LAST HDL_TAP TRUE
J 0
(-2875 4175);
DISPLAY 1.234043 (-2875 4175);
PAINT GREEN (-2875 4175);
DISPLAY INVISIBLE (-2875 4175);
FORCEPROP 1 LAST PATH I119
J 0
(-3200 4300);
DISPLAY 0.936170 (-3200 4300);
PAINT GREEN (-3200 4300);
DISPLAY INVISIBLE (-3200 4300);
FORCEADD PVTT_ABC..1
(-850 2700);
FORCEPROP 3 LASTPIN (-850 2650) SIG_NAME PVTT_ABC\g
J 0
(-840 2660);
DISPLAY 0.659574 (-840 2660);
PAINT MONO (-840 2660);
DISPLAY INVISIBLE (-840 2660);
FORCEPROP 1 LAST VOLTAGE 0.6V
J 0
(-895 2657);
DISPLAY 0.340426 (-895 2657);
PAINT SKYBLUE (-895 2657);
DISPLAY INVISIBLE (-895 2657);
FORCEPROP 2 LAST BOM_COST MEM
J 0
(-850 2705);
PAINT ORANGE (-850 2705);
DISPLAY INVISIBLE (-850 2705);
FORCEPROP 2 LAST CDS_LIB mstr_symbols
J 0
(-850 2700);
PAINT ORANGE (-850 2700);
DISPLAY INVISIBLE (-850 2700);
FORCEPROP 1 LAST BODY_TYPE PLUMBING
J 0
(-895 2657);
DISPLAY 0.340426 (-895 2657);
PAINT GREEN (-895 2657);
DISPLAY INVISIBLE (-895 2657);
FORCEPROP 1 LAST PATH I12
J 0
(-800 2725);
DISPLAY 0.872340 (-800 2725);
PAINT AQUA (-800 2725);
DISPLAY INVISIBLE (-800 2725);
FORCEPROP 2 LAST ROOM DDR4_CH_A
J 0
(-850 2800);
DISPLAY 0.787234 (-850 2800);
PAINT ORANGE (-850 2800);
DISPLAY INVISIBLE (-850 2800);
FORCEPROP 1 LAST HDL_POWER PVTT_ABC
J 1
(-850 2750);
DISPLAY 0.872340 (-850 2750);
PAINT GREEN (-850 2750);
DISPLAY INVISIBLE (-850 2750);
FORCEADD TAP..6
(-3200 4250);
FORCEPROP 3 LASTPIN (-3150 4250) SIG_NAME M_C_MA<9>
J 0
(-3140 4260);
DISPLAY 0.659574 (-3140 4260);
PAINT MONO (-3140 4260);
DISPLAY INVISIBLE (-3140 4260);
FORCEPROP 1 LASTPIN (-3150 4250) BN 9
J 0
(-3200 4260);
DISPLAY 0.617021 (-3200 4260);
PAINT PINK (-3200 4260);
FORCEPROP 2 LAST CDS_LIB mstr_standard
J 2
(-3200 4250);
DISPLAY 0.787234 (-3200 4250);
PAINT MONO (-3200 4250);
DISPLAY INVISIBLE (-3200 4250);
FORCEPROP 1 LAST BODY_TYPE PLUMBING
J 0
(-3200 4200);
DISPLAY 1.234043 (-3200 4200);
PAINT GREEN (-3200 4200);
DISPLAY INVISIBLE (-3200 4200);
FORCEPROP 1 LAST HDL_TAP TRUE
J 0
(-2875 4125);
DISPLAY 1.234043 (-2875 4125);
PAINT GREEN (-2875 4125);
DISPLAY INVISIBLE (-2875 4125);
FORCEPROP 1 LAST PATH I120
J 0
(-3200 4250);
DISPLAY 0.936170 (-3200 4250);
PAINT GREEN (-3200 4250);
DISPLAY INVISIBLE (-3200 4250);
FORCEADD TAP..6
(-3200 4200);
FORCEPROP 3 LASTPIN (-3150 4200) SIG_NAME M_C_MA<8>
J 0
(-3140 4210);
DISPLAY 0.659574 (-3140 4210);
PAINT MONO (-3140 4210);
DISPLAY INVISIBLE (-3140 4210);
FORCEPROP 1 LASTPIN (-3150 4200) BN 8
J 0
(-3200 4210);
DISPLAY 0.617021 (-3200 4210);
PAINT PINK (-3200 4210);
FORCEPROP 2 LAST CDS_LIB mstr_standard
J 2
(-3200 4200);
DISPLAY 0.787234 (-3200 4200);
PAINT MONO (-3200 4200);
DISPLAY INVISIBLE (-3200 4200);
FORCEPROP 1 LAST BODY_TYPE PLUMBING
J 0
(-3200 4150);
DISPLAY 1.234043 (-3200 4150);
PAINT GREEN (-3200 4150);
DISPLAY INVISIBLE (-3200 4150);
FORCEPROP 1 LAST HDL_TAP TRUE
J 0
(-2875 4075);
DISPLAY 1.234043 (-2875 4075);
PAINT GREEN (-2875 4075);
DISPLAY INVISIBLE (-2875 4075);
FORCEPROP 1 LAST PATH I121
J 0
(-3200 4200);
DISPLAY 0.936170 (-3200 4200);
PAINT GREEN (-3200 4200);
DISPLAY INVISIBLE (-3200 4200);
FORCEADD TAP..6
(-3200 4150);
FORCEPROP 3 LASTPIN (-3150 4150) SIG_NAME M_C_MA<7>
J 0
(-3140 4160);
DISPLAY 0.659574 (-3140 4160);
PAINT MONO (-3140 4160);
DISPLAY INVISIBLE (-3140 4160);
FORCEPROP 1 LASTPIN (-3150 4150) BN 7
J 0
(-3200 4160);
DISPLAY 0.617021 (-3200 4160);
PAINT PINK (-3200 4160);
FORCEPROP 2 LAST CDS_LIB mstr_standard
J 2
(-3200 4150);
DISPLAY 0.787234 (-3200 4150);
PAINT MONO (-3200 4150);
DISPLAY INVISIBLE (-3200 4150);
FORCEPROP 1 LAST BODY_TYPE PLUMBING
J 0
(-3200 4100);
DISPLAY 1.234043 (-3200 4100);
PAINT GREEN (-3200 4100);
DISPLAY INVISIBLE (-3200 4100);
FORCEPROP 1 LAST HDL_TAP TRUE
J 0
(-2875 4025);
DISPLAY 1.234043 (-2875 4025);
PAINT GREEN (-2875 4025);
DISPLAY INVISIBLE (-2875 4025);
FORCEPROP 1 LAST PATH I122
J 0
(-3200 4150);
DISPLAY 0.936170 (-3200 4150);
PAINT GREEN (-3200 4150);
DISPLAY INVISIBLE (-3200 4150);
FORCEADD TAP..6
(-3200 4100);
FORCEPROP 3 LASTPIN (-3150 4100) SIG_NAME M_C_MA<6>
J 0
(-3140 4110);
DISPLAY 0.659574 (-3140 4110);
PAINT MONO (-3140 4110);
DISPLAY INVISIBLE (-3140 4110);
FORCEPROP 1 LASTPIN (-3150 4100) BN 6
J 0
(-3200 4110);
DISPLAY 0.617021 (-3200 4110);
PAINT PINK (-3200 4110);
FORCEPROP 2 LAST CDS_LIB mstr_standard
J 2
(-3200 4100);
DISPLAY 0.787234 (-3200 4100);
PAINT MONO (-3200 4100);
DISPLAY INVISIBLE (-3200 4100);
FORCEPROP 1 LAST BODY_TYPE PLUMBING
J 0
(-3200 4050);
DISPLAY 1.234043 (-3200 4050);
PAINT GREEN (-3200 4050);
DISPLAY INVISIBLE (-3200 4050);
FORCEPROP 1 LAST HDL_TAP TRUE
J 0
(-2875 3975);
DISPLAY 1.234043 (-2875 3975);
PAINT GREEN (-2875 3975);
DISPLAY INVISIBLE (-2875 3975);
FORCEPROP 1 LAST PATH I123
J 0
(-3200 4100);
DISPLAY 0.936170 (-3200 4100);
PAINT GREEN (-3200 4100);
DISPLAY INVISIBLE (-3200 4100);
FORCEADD TAP..6
(-3200 4050);
FORCEPROP 3 LASTPIN (-3150 4050) SIG_NAME M_C_MA<5>
J 0
(-3140 4060);
DISPLAY 0.659574 (-3140 4060);
PAINT MONO (-3140 4060);
DISPLAY INVISIBLE (-3140 4060);
FORCEPROP 1 LASTPIN (-3150 4050) BN 5
J 0
(-3200 4060);
DISPLAY 0.617021 (-3200 4060);
PAINT PINK (-3200 4060);
FORCEPROP 2 LAST CDS_LIB mstr_standard
J 2
(-3200 4050);
DISPLAY 0.787234 (-3200 4050);
PAINT MONO (-3200 4050);
DISPLAY INVISIBLE (-3200 4050);
FORCEPROP 1 LAST BODY_TYPE PLUMBING
J 0
(-3200 4000);
DISPLAY 1.234043 (-3200 4000);
PAINT GREEN (-3200 4000);
DISPLAY INVISIBLE (-3200 4000);
FORCEPROP 1 LAST HDL_TAP TRUE
J 0
(-2875 3925);
DISPLAY 1.234043 (-2875 3925);
PAINT GREEN (-2875 3925);
DISPLAY INVISIBLE (-2875 3925);
FORCEPROP 1 LAST PATH I124
J 0
(-3200 4050);
DISPLAY 0.936170 (-3200 4050);
PAINT GREEN (-3200 4050);
DISPLAY INVISIBLE (-3200 4050);
FORCEADD TAP..6
(-3200 4000);
FORCEPROP 3 LASTPIN (-3150 4000) SIG_NAME M_C_MA<4>
J 0
(-3140 4010);
DISPLAY 0.659574 (-3140 4010);
PAINT MONO (-3140 4010);
DISPLAY INVISIBLE (-3140 4010);
FORCEPROP 1 LASTPIN (-3150 4000) BN 4
J 0
(-3200 4010);
DISPLAY 0.617021 (-3200 4010);
PAINT PINK (-3200 4010);
FORCEPROP 2 LAST CDS_LIB mstr_standard
J 2
(-3200 4000);
DISPLAY 0.787234 (-3200 4000);
PAINT MONO (-3200 4000);
DISPLAY INVISIBLE (-3200 4000);
FORCEPROP 1 LAST BODY_TYPE PLUMBING
J 0
(-3200 3950);
DISPLAY 1.234043 (-3200 3950);
PAINT GREEN (-3200 3950);
DISPLAY INVISIBLE (-3200 3950);
FORCEPROP 1 LAST HDL_TAP TRUE
J 0
(-2875 3875);
DISPLAY 1.234043 (-2875 3875);
PAINT GREEN (-2875 3875);
DISPLAY INVISIBLE (-2875 3875);
FORCEPROP 1 LAST PATH I125
J 0
(-3200 4000);
DISPLAY 0.936170 (-3200 4000);
PAINT GREEN (-3200 4000);
DISPLAY INVISIBLE (-3200 4000);
FORCEADD TAP..6
(-3200 3950);
FORCEPROP 3 LASTPIN (-3150 3950) SIG_NAME M_C_MA<3>
J 0
(-3140 3960);
DISPLAY 0.659574 (-3140 3960);
PAINT MONO (-3140 3960);
DISPLAY INVISIBLE (-3140 3960);
FORCEPROP 1 LASTPIN (-3150 3950) BN 3
J 0
(-3200 3960);
DISPLAY 0.617021 (-3200 3960);
PAINT PINK (-3200 3960);
FORCEPROP 2 LAST CDS_LIB mstr_standard
J 2
(-3200 3950);
DISPLAY 0.787234 (-3200 3950);
PAINT MONO (-3200 3950);
DISPLAY INVISIBLE (-3200 3950);
FORCEPROP 1 LAST BODY_TYPE PLUMBING
J 0
(-3200 3900);
DISPLAY 1.234043 (-3200 3900);
PAINT GREEN (-3200 3900);
DISPLAY INVISIBLE (-3200 3900);
FORCEPROP 1 LAST HDL_TAP TRUE
J 0
(-2875 3825);
DISPLAY 1.234043 (-2875 3825);
PAINT GREEN (-2875 3825);
DISPLAY INVISIBLE (-2875 3825);
FORCEPROP 1 LAST PATH I126
J 0
(-3200 3950);
DISPLAY 0.936170 (-3200 3950);
PAINT GREEN (-3200 3950);
DISPLAY INVISIBLE (-3200 3950);
FORCEADD OFFPAGE..1
(-3800 4700);
FORCEPROP 2 LAST $XR1 48 
J 0
(-4141 4700);
DISPLAY 0.638298 (-4141 4700);
PAINT MONO (-4141 4700);
FORCEPROP 2 LAST $XR0 25 
J 0
(-4051 4700);
DISPLAY 0.638298 (-4051 4700);
PAINT MONO (-4051 4700);
FORCEPROP 2 LAST CDS_LIB mstr_standard
J 0
(-3800 4700);
DISPLAY 0.787234 (-3800 4700);
PAINT MONO (-3800 4700);
DISPLAY INVISIBLE (-3800 4700);
FORCEPROP 1 LAST OFFPAGE TRUE
J 0
(-3475 4575);
DISPLAY 0.936170 (-3475 4575);
PAINT GREEN (-3475 4575);
DISPLAY INVISIBLE (-3475 4575);
FORCEPROP 1 LAST COMMENT_BODY TRUE
J 0
(-3675 4600);
DISPLAY 0.936170 (-3675 4600);
PAINT GREEN (-3675 4600);
DISPLAY INVISIBLE (-3675 4600);
FORCEPROP 2 LAST PATH I127
J 0
(-3750 4775);
DISPLAY 0.787234 (-3750 4775);
PAINT MONO (-3750 4775);
DISPLAY INVISIBLE (-3750 4775);
FORCEADD TAP..6
(-3200 3900);
FORCEPROP 3 LASTPIN (-3150 3900) SIG_NAME M_C_MA<2>
J 0
(-3140 3910);
DISPLAY 0.659574 (-3140 3910);
PAINT MONO (-3140 3910);
DISPLAY INVISIBLE (-3140 3910);
FORCEPROP 1 LASTPIN (-3150 3900) BN 2
J 0
(-3200 3910);
DISPLAY 0.617021 (-3200 3910);
PAINT PINK (-3200 3910);
FORCEPROP 2 LAST CDS_LIB mstr_standard
J 2
(-3200 3900);
DISPLAY 0.787234 (-3200 3900);
PAINT MONO (-3200 3900);
DISPLAY INVISIBLE (-3200 3900);
FORCEPROP 1 LAST BODY_TYPE PLUMBING
J 0
(-3200 3850);
DISPLAY 1.234043 (-3200 3850);
PAINT GREEN (-3200 3850);
DISPLAY INVISIBLE (-3200 3850);
FORCEPROP 1 LAST HDL_TAP TRUE
J 0
(-2875 3775);
DISPLAY 1.234043 (-2875 3775);
PAINT GREEN (-2875 3775);
DISPLAY INVISIBLE (-2875 3775);
FORCEPROP 1 LAST PATH I128
J 0
(-3200 3900);
DISPLAY 0.936170 (-3200 3900);
PAINT GREEN (-3200 3900);
DISPLAY INVISIBLE (-3200 3900);
FORCEADD TAP..6
(-3200 3850);
FORCEPROP 3 LASTPIN (-3150 3850) SIG_NAME M_C_MA<1>
J 0
(-3140 3860);
DISPLAY 0.659574 (-3140 3860);
PAINT MONO (-3140 3860);
DISPLAY INVISIBLE (-3140 3860);
FORCEPROP 1 LASTPIN (-3150 3850) BN 1
J 0
(-3200 3860);
DISPLAY 0.617021 (-3200 3860);
PAINT PINK (-3200 3860);
FORCEPROP 2 LAST CDS_LIB mstr_standard
J 2
(-3200 3850);
DISPLAY 0.787234 (-3200 3850);
PAINT MONO (-3200 3850);
DISPLAY INVISIBLE (-3200 3850);
FORCEPROP 1 LAST BODY_TYPE PLUMBING
J 0
(-3200 3800);
DISPLAY 1.234043 (-3200 3800);
PAINT GREEN (-3200 3800);
DISPLAY INVISIBLE (-3200 3800);
FORCEPROP 1 LAST HDL_TAP TRUE
J 0
(-2875 3725);
DISPLAY 1.234043 (-2875 3725);
PAINT GREEN (-2875 3725);
DISPLAY INVISIBLE (-2875 3725);
FORCEPROP 1 LAST PATH I129
J 0
(-3200 3850);
DISPLAY 0.936170 (-3200 3850);
PAINT GREEN (-3200 3850);
DISPLAY INVISIBLE (-3200 3850);
FORCEADD PVDDQ_ABC..1
(-1150 2600);
FORCEPROP 3 LASTPIN (-1150 2550) SIG_NAME PVDDQ_ABC\g
J 0
(-1140 2560);
DISPLAY 0.659574 (-1140 2560);
PAINT MONO (-1140 2560);
DISPLAY INVISIBLE (-1140 2560);
FORCEPROP 1 LAST VOLTAGE 1.2V
J 0
(-1195 2557);
DISPLAY 0.340426 (-1195 2557);
PAINT SKYBLUE (-1195 2557);
DISPLAY INVISIBLE (-1195 2557);
FORCEPROP 2 LAST BOM_COST MEM
J 0
(-1150 2605);
PAINT ORANGE (-1150 2605);
DISPLAY INVISIBLE (-1150 2605);
FORCEPROP 2 LAST CDS_LIB mstr_symbols
J 0
(-1150 2600);
PAINT ORANGE (-1150 2600);
DISPLAY INVISIBLE (-1150 2600);
FORCEPROP 1 LAST BODY_TYPE PLUMBING
J 0
(-1195 2557);
DISPLAY 0.340426 (-1195 2557);
PAINT GREEN (-1195 2557);
DISPLAY INVISIBLE (-1195 2557);
FORCEPROP 1 LAST PATH I13
J 0
(-1100 2625);
DISPLAY 0.872340 (-1100 2625);
PAINT AQUA (-1100 2625);
DISPLAY INVISIBLE (-1100 2625);
FORCEPROP 2 LAST ROOM DDR4_CH_A
J 0
(-1150 2700);
DISPLAY 0.787234 (-1150 2700);
PAINT ORANGE (-1150 2700);
DISPLAY INVISIBLE (-1150 2700);
FORCEPROP 1 LAST HDL_POWER PVDDQ_ABC
J 1
(-1150 2650);
DISPLAY 0.872340 (-1150 2650);
PAINT GREEN (-1150 2650);
DISPLAY INVISIBLE (-1150 2650);
FORCEADD TAP..6
(-3200 3800);
FORCEPROP 3 LASTPIN (-3150 3800) SIG_NAME M_C_MA<0>
J 0
(-3140 3810);
DISPLAY 0.659574 (-3140 3810);
PAINT MONO (-3140 3810);
DISPLAY INVISIBLE (-3140 3810);
FORCEPROP 1 LASTPIN (-3150 3800) BN 0
J 0
(-3200 3810);
DISPLAY 0.617021 (-3200 3810);
PAINT PINK (-3200 3810);
FORCEPROP 2 LAST CDS_LIB mstr_standard
J 2
(-3200 3800);
DISPLAY 0.787234 (-3200 3800);
PAINT MONO (-3200 3800);
DISPLAY INVISIBLE (-3200 3800);
FORCEPROP 1 LAST BODY_TYPE PLUMBING
J 0
(-3200 3750);
DISPLAY 1.234043 (-3200 3750);
PAINT GREEN (-3200 3750);
DISPLAY INVISIBLE (-3200 3750);
FORCEPROP 1 LAST HDL_TAP TRUE
J 0
(-2875 3675);
DISPLAY 1.234043 (-2875 3675);
PAINT GREEN (-2875 3675);
DISPLAY INVISIBLE (-2875 3675);
FORCEPROP 1 LAST PATH I130
J 0
(-3200 3800);
DISPLAY 0.936170 (-3200 3800);
PAINT GREEN (-3200 3800);
DISPLAY INVISIBLE (-3200 3800);
FORCEADD TAP..6
(-3200 3700);
FORCEPROP 3 LASTPIN (-3150 3700) SIG_NAME M_C_BA<1>
J 0
(-3140 3710);
DISPLAY 0.659574 (-3140 3710);
PAINT MONO (-3140 3710);
DISPLAY INVISIBLE (-3140 3710);
FORCEPROP 1 LASTPIN (-3150 3700) BN 1
J 0
(-3200 3710);
DISPLAY 0.617021 (-3200 3710);
PAINT PINK (-3200 3710);
FORCEPROP 2 LAST CDS_LIB mstr_standard
J 0
(-3200 3700);
DISPLAY 0.787234 (-3200 3700);
PAINT MONO (-3200 3700);
DISPLAY INVISIBLE (-3200 3700);
FORCEPROP 1 LAST BODY_TYPE PLUMBING
J 0
(-3200 3650);
DISPLAY 1.234043 (-3200 3650);
PAINT GREEN (-3200 3650);
DISPLAY INVISIBLE (-3200 3650);
FORCEPROP 1 LAST HDL_TAP TRUE
J 0
(-2875 3575);
DISPLAY 1.234043 (-2875 3575);
PAINT GREEN (-2875 3575);
DISPLAY INVISIBLE (-2875 3575);
FORCEPROP 1 LAST PATH I131
J 0
(-3200 3700);
DISPLAY 0.936170 (-3200 3700);
PAINT GREEN (-3200 3700);
DISPLAY INVISIBLE (-3200 3700);
FORCEADD TAP..6
(-3200 3650);
FORCEPROP 3 LASTPIN (-3150 3650) SIG_NAME M_C_BA<0>
J 0
(-3140 3660);
DISPLAY 0.659574 (-3140 3660);
PAINT MONO (-3140 3660);
DISPLAY INVISIBLE (-3140 3660);
FORCEPROP 1 LASTPIN (-3150 3650) BN 0
J 0
(-3200 3660);
DISPLAY 0.617021 (-3200 3660);
PAINT PINK (-3200 3660);
FORCEPROP 2 LAST CDS_LIB mstr_standard
J 0
(-3200 3650);
DISPLAY 0.787234 (-3200 3650);
PAINT MONO (-3200 3650);
DISPLAY INVISIBLE (-3200 3650);
FORCEPROP 1 LAST BODY_TYPE PLUMBING
J 0
(-3200 3600);
DISPLAY 1.234043 (-3200 3600);
PAINT GREEN (-3200 3600);
DISPLAY INVISIBLE (-3200 3600);
FORCEPROP 1 LAST HDL_TAP TRUE
J 0
(-2875 3525);
DISPLAY 1.234043 (-2875 3525);
PAINT GREEN (-2875 3525);
DISPLAY INVISIBLE (-2875 3525);
FORCEPROP 1 LAST PATH I132
J 0
(-3200 3650);
DISPLAY 0.936170 (-3200 3650);
PAINT GREEN (-3200 3650);
DISPLAY INVISIBLE (-3200 3650);
FORCEADD TAP..6
(-3200 3550);
FORCEPROP 3 LASTPIN (-3150 3550) SIG_NAME M_C_BG<0>
J 0
(-3140 3560);
DISPLAY 0.659574 (-3140 3560);
PAINT MONO (-3140 3560);
DISPLAY INVISIBLE (-3140 3560);
FORCEPROP 1 LASTPIN (-3150 3550) BN 0
J 0
(-3200 3560);
DISPLAY 0.617021 (-3200 3560);
PAINT PINK (-3200 3560);
FORCEPROP 2 LAST CDS_LIB mstr_standard
J 0
(-3200 3550);
DISPLAY 0.787234 (-3200 3550);
PAINT MONO (-3200 3550);
DISPLAY INVISIBLE (-3200 3550);
FORCEPROP 1 LAST BODY_TYPE PLUMBING
J 0
(-3200 3500);
DISPLAY 1.234043 (-3200 3500);
PAINT GREEN (-3200 3500);
DISPLAY INVISIBLE (-3200 3500);
FORCEPROP 1 LAST HDL_TAP TRUE
J 0
(-2875 3425);
DISPLAY 1.234043 (-2875 3425);
PAINT GREEN (-2875 3425);
DISPLAY INVISIBLE (-2875 3425);
FORCEPROP 1 LAST PATH I133
J 0
(-3200 3550);
DISPLAY 0.936170 (-3200 3550);
PAINT GREEN (-3200 3550);
DISPLAY INVISIBLE (-3200 3550);
FORCEADD TAP..6
(-3200 3600);
FORCEPROP 3 LASTPIN (-3150 3600) SIG_NAME M_C_BG<1>
J 0
(-3140 3610);
DISPLAY 0.659574 (-3140 3610);
PAINT MONO (-3140 3610);
DISPLAY INVISIBLE (-3140 3610);
FORCEPROP 1 LASTPIN (-3150 3600) BN 1
J 0
(-3200 3610);
DISPLAY 0.617021 (-3200 3610);
PAINT PINK (-3200 3610);
FORCEPROP 2 LAST CDS_LIB mstr_standard
J 0
(-3200 3600);
DISPLAY 0.787234 (-3200 3600);
PAINT MONO (-3200 3600);
DISPLAY INVISIBLE (-3200 3600);
FORCEPROP 1 LAST BODY_TYPE PLUMBING
J 0
(-3200 3550);
DISPLAY 1.234043 (-3200 3550);
PAINT GREEN (-3200 3550);
DISPLAY INVISIBLE (-3200 3550);
FORCEPROP 1 LAST HDL_TAP TRUE
J 0
(-2875 3475);
DISPLAY 1.234043 (-2875 3475);
PAINT GREEN (-2875 3475);
DISPLAY INVISIBLE (-2875 3475);
FORCEPROP 1 LAST PATH I134
J 0
(-3200 3600);
DISPLAY 0.936170 (-3200 3600);
PAINT GREEN (-3200 3600);
DISPLAY INVISIBLE (-3200 3600);
FORCEADD OFFPAGE..1
(-3800 3250);
FORCEPROP 2 LAST $XR1 48 
J 0
(-4141 3250);
DISPLAY 0.638298 (-4141 3250);
PAINT MONO (-4141 3250);
FORCEPROP 2 LAST $XR0 25 
J 0
(-4051 3250);
DISPLAY 0.638298 (-4051 3250);
PAINT MONO (-4051 3250);
FORCEPROP 2 LAST CDS_LIB mstr_standard
J 0
(-3800 3250);
DISPLAY 0.787234 (-3800 3250);
PAINT MONO (-3800 3250);
DISPLAY INVISIBLE (-3800 3250);
FORCEPROP 1 LAST OFFPAGE TRUE
J 0
(-3475 3125);
DISPLAY 0.936170 (-3475 3125);
PAINT GREEN (-3475 3125);
DISPLAY INVISIBLE (-3475 3125);
FORCEPROP 1 LAST COMMENT_BODY TRUE
J 0
(-3675 3150);
DISPLAY 0.936170 (-3675 3150);
PAINT GREEN (-3675 3150);
DISPLAY INVISIBLE (-3675 3150);
FORCEPROP 2 LAST PATH I135
J 0
(-3750 3325);
DISPLAY 0.787234 (-3750 3325);
PAINT MONO (-3750 3325);
DISPLAY INVISIBLE (-3750 3325);
FORCEADD OFFPAGE..1
(-3800 3750);
FORCEPROP 2 LAST $XR1 48 
J 0
(-4141 3750);
DISPLAY 0.638298 (-4141 3750);
PAINT MONO (-4141 3750);
FORCEPROP 2 LAST $XR0 25 
J 0
(-4051 3750);
DISPLAY 0.638298 (-4051 3750);
PAINT MONO (-4051 3750);
FORCEPROP 2 LAST CDS_LIB mstr_standard
J 0
(-3800 3750);
DISPLAY 0.787234 (-3800 3750);
PAINT MONO (-3800 3750);
DISPLAY INVISIBLE (-3800 3750);
FORCEPROP 1 LAST OFFPAGE TRUE
J 0
(-3475 3625);
DISPLAY 0.936170 (-3475 3625);
PAINT GREEN (-3475 3625);
DISPLAY INVISIBLE (-3475 3625);
FORCEPROP 1 LAST COMMENT_BODY TRUE
J 0
(-3675 3650);
DISPLAY 0.936170 (-3675 3650);
PAINT GREEN (-3675 3650);
DISPLAY INVISIBLE (-3675 3650);
FORCEPROP 2 LAST PATH I136
J 0
(-3750 3825);
DISPLAY 0.787234 (-3750 3825);
PAINT MONO (-3750 3825);
DISPLAY INVISIBLE (-3750 3825);
FORCEADD OFFPAGE..1
(-3800 3650);
FORCEPROP 2 LAST $XR1 48 
J 0
(-4141 3650);
DISPLAY 0.638298 (-4141 3650);
PAINT MONO (-4141 3650);
FORCEPROP 2 LAST $XR0 25 
J 0
(-4051 3650);
DISPLAY 0.638298 (-4051 3650);
PAINT MONO (-4051 3650);
FORCEPROP 2 LAST CDS_LIB mstr_standard
J 0
(-3800 3650);
DISPLAY 0.787234 (-3800 3650);
PAINT MONO (-3800 3650);
DISPLAY INVISIBLE (-3800 3650);
FORCEPROP 1 LAST OFFPAGE TRUE
J 0
(-3475 3525);
DISPLAY 0.936170 (-3475 3525);
PAINT GREEN (-3475 3525);
DISPLAY INVISIBLE (-3475 3525);
FORCEPROP 1 LAST COMMENT_BODY TRUE
J 0
(-3675 3550);
DISPLAY 0.936170 (-3675 3550);
PAINT GREEN (-3675 3550);
DISPLAY INVISIBLE (-3675 3550);
FORCEPROP 2 LAST PATH I137
J 0
(-3750 3725);
DISPLAY 0.787234 (-3750 3725);
PAINT MONO (-3750 3725);
DISPLAY INVISIBLE (-3750 3725);
FORCEADD TAP..6
(-3200 2600);
FORCEPROP 3 LASTPIN (-3150 2600) SIG_NAME M_C_ECC<6>
J 0
(-3140 2610);
DISPLAY 0.659574 (-3140 2610);
PAINT MONO (-3140 2610);
DISPLAY INVISIBLE (-3140 2610);
FORCEPROP 1 LASTPIN (-3150 2600) BN 6
J 0
(-3200 2610);
DISPLAY 0.617021 (-3200 2610);
PAINT PINK (-3200 2610);
FORCEPROP 2 LAST CDS_LIB mstr_standard
J 0
(-3200 2600);
DISPLAY 0.787234 (-3200 2600);
PAINT MONO (-3200 2600);
DISPLAY INVISIBLE (-3200 2600);
FORCEPROP 1 LAST BODY_TYPE PLUMBING
J 0
(-3200 2550);
DISPLAY 1.234043 (-3200 2550);
PAINT GREEN (-3200 2550);
DISPLAY INVISIBLE (-3200 2550);
FORCEPROP 1 LAST HDL_TAP TRUE
J 0
(-2875 2475);
DISPLAY 1.234043 (-2875 2475);
PAINT GREEN (-2875 2475);
DISPLAY INVISIBLE (-2875 2475);
FORCEPROP 1 LAST PATH I138
J 0
(-3200 2600);
DISPLAY 0.936170 (-3200 2600);
PAINT GREEN (-3200 2600);
DISPLAY INVISIBLE (-3200 2600);
FORCEADD TAP..6
(-3200 2550);
FORCEPROP 3 LASTPIN (-3150 2550) SIG_NAME M_C_ECC<7>
J 0
(-3140 2560);
DISPLAY 0.659574 (-3140 2560);
PAINT MONO (-3140 2560);
DISPLAY INVISIBLE (-3140 2560);
FORCEPROP 1 LASTPIN (-3150 2550) BN 7
J 0
(-3200 2560);
DISPLAY 0.617021 (-3200 2560);
PAINT PINK (-3200 2560);
FORCEPROP 2 LAST CDS_LIB mstr_standard
J 0
(-3200 2550);
DISPLAY 0.787234 (-3200 2550);
PAINT MONO (-3200 2550);
DISPLAY INVISIBLE (-3200 2550);
FORCEPROP 1 LAST BODY_TYPE PLUMBING
J 0
(-3200 2500);
DISPLAY 1.234043 (-3200 2500);
PAINT GREEN (-3200 2500);
DISPLAY INVISIBLE (-3200 2500);
FORCEPROP 1 LAST HDL_TAP TRUE
J 0
(-2875 2425);
DISPLAY 1.234043 (-2875 2425);
PAINT GREEN (-2875 2425);
DISPLAY INVISIBLE (-2875 2425);
FORCEPROP 1 LAST PATH I139
J 0
(-3200 2550);
DISPLAY 0.936170 (-3200 2550);
PAINT GREEN (-3200 2550);
DISPLAY INVISIBLE (-3200 2550);
FORCEADD TAP..6
R 2
(900 4650);
FORCEPROP 3 LASTPIN (850 4650) SIG_NAME M_C_DQS_DN<12>
J 0
(860 4660);
DISPLAY 0.659574 (860 4660);
PAINT MONO (860 4660);
DISPLAY INVISIBLE (860 4660);
FORCEPROP 1 LASTPIN (850 4650) BN 12
J 2
(900 4660);
DISPLAY 0.617021 (900 4660);
PAINT PINK (900 4660);
FORCEPROP 2 LAST CDS_LIB mstr_standard
J 0
(900 4650);
DISPLAY 0.787234 (900 4650);
PAINT MONO (900 4650);
DISPLAY INVISIBLE (900 4650);
FORCEPROP 1 LAST BODY_TYPE PLUMBING
J 2
(900 4600);
DISPLAY 1.234043 (900 4600);
PAINT GREEN (900 4600);
DISPLAY INVISIBLE (900 4600);
FORCEPROP 1 LAST HDL_TAP TRUE
J 2
(575 4525);
DISPLAY 1.234043 (575 4525);
PAINT GREEN (575 4525);
DISPLAY INVISIBLE (575 4525);
FORCEPROP 1 LAST PATH I14
J 2
(900 4650);
DISPLAY 0.936170 (900 4650);
PAINT GREEN (900 4650);
DISPLAY INVISIBLE (900 4650);
FORCEADD TAP..6
(-3200 2500);
FORCEPROP 3 LASTPIN (-3150 2500) SIG_NAME M_C_ECC<4>
J 0
(-3140 2510);
DISPLAY 0.659574 (-3140 2510);
PAINT MONO (-3140 2510);
DISPLAY INVISIBLE (-3140 2510);
FORCEPROP 1 LASTPIN (-3150 2500) BN 4
J 0
(-3200 2510);
DISPLAY 0.617021 (-3200 2510);
PAINT PINK (-3200 2510);
FORCEPROP 2 LAST CDS_LIB mstr_standard
J 0
(-3200 2500);
DISPLAY 0.787234 (-3200 2500);
PAINT MONO (-3200 2500);
DISPLAY INVISIBLE (-3200 2500);
FORCEPROP 1 LAST BODY_TYPE PLUMBING
J 0
(-3200 2450);
DISPLAY 1.234043 (-3200 2450);
PAINT GREEN (-3200 2450);
DISPLAY INVISIBLE (-3200 2450);
FORCEPROP 1 LAST HDL_TAP TRUE
J 0
(-2875 2375);
DISPLAY 1.234043 (-2875 2375);
PAINT GREEN (-2875 2375);
DISPLAY INVISIBLE (-2875 2375);
FORCEPROP 1 LAST PATH I140
J 0
(-3200 2500);
DISPLAY 0.936170 (-3200 2500);
PAINT GREEN (-3200 2500);
DISPLAY INVISIBLE (-3200 2500);
FORCEADD TAP..6
(-3200 2450);
FORCEPROP 3 LASTPIN (-3150 2450) SIG_NAME M_C_ECC<5>
J 0
(-3140 2460);
DISPLAY 0.659574 (-3140 2460);
PAINT MONO (-3140 2460);
DISPLAY INVISIBLE (-3140 2460);
FORCEPROP 1 LASTPIN (-3150 2450) BN 5
J 0
(-3200 2460);
DISPLAY 0.617021 (-3200 2460);
PAINT PINK (-3200 2460);
FORCEPROP 2 LAST CDS_LIB mstr_standard
J 0
(-3200 2450);
DISPLAY 0.787234 (-3200 2450);
PAINT MONO (-3200 2450);
DISPLAY INVISIBLE (-3200 2450);
FORCEPROP 1 LAST BODY_TYPE PLUMBING
J 0
(-3200 2400);
DISPLAY 1.234043 (-3200 2400);
PAINT GREEN (-3200 2400);
DISPLAY INVISIBLE (-3200 2400);
FORCEPROP 1 LAST HDL_TAP TRUE
J 0
(-2875 2325);
DISPLAY 1.234043 (-2875 2325);
PAINT GREEN (-2875 2325);
DISPLAY INVISIBLE (-2875 2325);
FORCEPROP 1 LAST PATH I141
J 0
(-3200 2450);
DISPLAY 0.936170 (-3200 2450);
PAINT GREEN (-3200 2450);
DISPLAY INVISIBLE (-3200 2450);
FORCEADD TAP..6
(-3200 2400);
FORCEPROP 3 LASTPIN (-3150 2400) SIG_NAME M_C_ECC<2>
J 0
(-3140 2410);
DISPLAY 0.659574 (-3140 2410);
PAINT MONO (-3140 2410);
DISPLAY INVISIBLE (-3140 2410);
FORCEPROP 1 LASTPIN (-3150 2400) BN 2
J 0
(-3200 2410);
DISPLAY 0.617021 (-3200 2410);
PAINT PINK (-3200 2410);
FORCEPROP 2 LAST CDS_LIB mstr_standard
J 0
(-3200 2400);
DISPLAY 0.787234 (-3200 2400);
PAINT MONO (-3200 2400);
DISPLAY INVISIBLE (-3200 2400);
FORCEPROP 1 LAST BODY_TYPE PLUMBING
J 0
(-3200 2350);
DISPLAY 1.234043 (-3200 2350);
PAINT GREEN (-3200 2350);
DISPLAY INVISIBLE (-3200 2350);
FORCEPROP 1 LAST HDL_TAP TRUE
J 0
(-2875 2275);
DISPLAY 1.234043 (-2875 2275);
PAINT GREEN (-2875 2275);
DISPLAY INVISIBLE (-2875 2275);
FORCEPROP 1 LAST PATH I142
J 0
(-3200 2400);
DISPLAY 0.936170 (-3200 2400);
PAINT GREEN (-3200 2400);
DISPLAY INVISIBLE (-3200 2400);
FORCEADD TAP..6
(-3200 2350);
FORCEPROP 3 LASTPIN (-3150 2350) SIG_NAME M_C_ECC<3>
J 0
(-3140 2360);
DISPLAY 0.659574 (-3140 2360);
PAINT MONO (-3140 2360);
DISPLAY INVISIBLE (-3140 2360);
FORCEPROP 1 LASTPIN (-3150 2350) BN 3
J 0
(-3200 2360);
DISPLAY 0.617021 (-3200 2360);
PAINT PINK (-3200 2360);
FORCEPROP 2 LAST CDS_LIB mstr_standard
J 0
(-3200 2350);
DISPLAY 0.787234 (-3200 2350);
PAINT MONO (-3200 2350);
DISPLAY INVISIBLE (-3200 2350);
FORCEPROP 1 LAST BODY_TYPE PLUMBING
J 0
(-3200 2300);
DISPLAY 1.234043 (-3200 2300);
PAINT GREEN (-3200 2300);
DISPLAY INVISIBLE (-3200 2300);
FORCEPROP 1 LAST HDL_TAP TRUE
J 0
(-2875 2225);
DISPLAY 1.234043 (-2875 2225);
PAINT GREEN (-2875 2225);
DISPLAY INVISIBLE (-2875 2225);
FORCEPROP 1 LAST PATH I143
J 0
(-3200 2350);
DISPLAY 0.936170 (-3200 2350);
PAINT GREEN (-3200 2350);
DISPLAY INVISIBLE (-3200 2350);
FORCEADD TAP..6
(-3200 2300);
FORCEPROP 3 LASTPIN (-3150 2300) SIG_NAME M_C_ECC<0>
J 0
(-3140 2310);
DISPLAY 0.659574 (-3140 2310);
PAINT MONO (-3140 2310);
DISPLAY INVISIBLE (-3140 2310);
FORCEPROP 1 LASTPIN (-3150 2300) BN 0
J 0
(-3200 2310);
DISPLAY 0.617021 (-3200 2310);
PAINT PINK (-3200 2310);
FORCEPROP 2 LAST CDS_LIB mstr_standard
J 0
(-3200 2300);
DISPLAY 0.787234 (-3200 2300);
PAINT MONO (-3200 2300);
DISPLAY INVISIBLE (-3200 2300);
FORCEPROP 1 LAST BODY_TYPE PLUMBING
J 0
(-3200 2250);
DISPLAY 1.234043 (-3200 2250);
PAINT GREEN (-3200 2250);
DISPLAY INVISIBLE (-3200 2250);
FORCEPROP 1 LAST HDL_TAP TRUE
J 0
(-2875 2175);
DISPLAY 1.234043 (-2875 2175);
PAINT GREEN (-2875 2175);
DISPLAY INVISIBLE (-2875 2175);
FORCEPROP 1 LAST PATH I144
J 0
(-3200 2300);
DISPLAY 0.936170 (-3200 2300);
PAINT GREEN (-3200 2300);
DISPLAY INVISIBLE (-3200 2300);
FORCEADD TAP..6
(-3200 2250);
FORCEPROP 3 LASTPIN (-3150 2250) SIG_NAME M_C_ECC<1>
J 0
(-3140 2260);
DISPLAY 0.659574 (-3140 2260);
PAINT MONO (-3140 2260);
DISPLAY INVISIBLE (-3140 2260);
FORCEPROP 1 LASTPIN (-3150 2250) BN 1
J 0
(-3200 2260);
DISPLAY 0.617021 (-3200 2260);
PAINT PINK (-3200 2260);
FORCEPROP 2 LAST CDS_LIB mstr_standard
J 0
(-3200 2250);
DISPLAY 0.787234 (-3200 2250);
PAINT MONO (-3200 2250);
DISPLAY INVISIBLE (-3200 2250);
FORCEPROP 1 LAST BODY_TYPE PLUMBING
J 0
(-3200 2200);
DISPLAY 1.234043 (-3200 2200);
PAINT GREEN (-3200 2200);
DISPLAY INVISIBLE (-3200 2200);
FORCEPROP 1 LAST HDL_TAP TRUE
J 0
(-2875 2125);
DISPLAY 1.234043 (-2875 2125);
PAINT GREEN (-2875 2125);
DISPLAY INVISIBLE (-2875 2125);
FORCEPROP 1 LAST PATH I145
J 0
(-3200 2250);
DISPLAY 0.936170 (-3200 2250);
PAINT GREEN (-3200 2250);
DISPLAY INVISIBLE (-3200 2250);
FORCEADD OFFPAGE..1
(-3800 2600);
FORCEPROP 2 LAST $XR1 48 
J 0
(-4141 2600);
DISPLAY 0.638298 (-4141 2600);
PAINT MONO (-4141 2600);
FORCEPROP 2 LAST $XR0 25 
J 0
(-4051 2600);
DISPLAY 0.638298 (-4051 2600);
PAINT MONO (-4051 2600);
FORCEPROP 2 LAST CDS_LIB mstr_standard
J 0
(-3800 2600);
DISPLAY 0.787234 (-3800 2600);
PAINT MONO (-3800 2600);
DISPLAY INVISIBLE (-3800 2600);
FORCEPROP 1 LAST OFFPAGE TRUE
J 0
(-3475 2475);
DISPLAY 0.936170 (-3475 2475);
PAINT GREEN (-3475 2475);
DISPLAY INVISIBLE (-3475 2475);
FORCEPROP 1 LAST COMMENT_BODY TRUE
J 0
(-3675 2500);
DISPLAY 0.936170 (-3675 2500);
PAINT GREEN (-3675 2500);
DISPLAY INVISIBLE (-3675 2500);
FORCEPROP 2 LAST PATH I146
J 0
(-3750 2675);
DISPLAY 0.787234 (-3750 2675);
PAINT MONO (-3750 2675);
DISPLAY INVISIBLE (-3750 2675);
FORCEADD OFFPAGE..1
(-3800 2550);
FORCEPROP 2 LAST $XR5 48 
J 0
(-4501 2550);
DISPLAY 0.638298 (-4501 2550);
PAINT MONO (-4501 2550);
FORCEPROP 2 LAST $XR4 46 
J 0
(-4411 2550);
DISPLAY 0.638298 (-4411 2550);
PAINT MONO (-4411 2550);
FORCEPROP 2 LAST $XR3 45 
J 0
(-4321 2550);
DISPLAY 0.638298 (-4321 2550);
PAINT MONO (-4321 2550);
FORCEPROP 2 LAST $XR2 44 
J 0
(-4231 2550);
DISPLAY 0.638298 (-4231 2550);
PAINT MONO (-4231 2550);
FORCEPROP 2 LAST $XR1 43 
J 0
(-4141 2550);
DISPLAY 0.638298 (-4141 2550);
PAINT MONO (-4141 2550);
FORCEPROP 2 LAST $XR0 21 
J 0
(-4051 2550);
DISPLAY 0.638298 (-4051 2550);
PAINT MONO (-4051 2550);
FORCEPROP 2 LAST CDS_LIB mstr_standard
J 0
(-3800 2550);
DISPLAY 0.787234 (-3800 2550);
PAINT MONO (-3800 2550);
DISPLAY INVISIBLE (-3800 2550);
FORCEPROP 1 LAST OFFPAGE TRUE
J 0
(-3475 2425);
DISPLAY 0.936170 (-3475 2425);
PAINT GREEN (-3475 2425);
DISPLAY INVISIBLE (-3475 2425);
FORCEPROP 1 LAST COMMENT_BODY TRUE
J 0
(-3675 2450);
DISPLAY 0.936170 (-3675 2450);
PAINT GREEN (-3675 2450);
DISPLAY INVISIBLE (-3675 2450);
FORCEPROP 2 LAST PATH I147
J 0
(-3750 2625);
DISPLAY 0.787234 (-3750 2625);
PAINT MONO (-3750 2625);
DISPLAY INVISIBLE (-3750 2625);
FORCEADD OFFPAGE..5
(-4025 2000);
FORCEPROP 2 LAST $XR1 25 
J 0
(-4339 2000);
DISPLAY 0.638298 (-4339 2000);
PAINT MONO (-4339 2000);
FORCEPROP 2 LAST $XR0 48 
J 0
(-4249 2000);
DISPLAY 0.638298 (-4249 2000);
PAINT MONO (-4249 2000);
FORCEPROP 2 LAST CDS_LIB mstr_standard
J 0
(-4025 2000);
DISPLAY 0.787234 (-4025 2000);
PAINT MONO (-4025 2000);
DISPLAY INVISIBLE (-4025 2000);
FORCEPROP 1 LAST OFFPAGE TRUE
J 0
(-3700 1875);
DISPLAY 1.404255 (-3700 1875);
PAINT GREEN (-3700 1875);
DISPLAY INVISIBLE (-3700 1875);
FORCEPROP 1 LAST COMMENT_BODY TRUE
J 0
(-3925 1925);
DISPLAY 1.404255 (-3925 1925);
PAINT GREEN (-3925 1925);
DISPLAY INVISIBLE (-3925 1925);
FORCEPROP 2 LAST PATH I148
J 0
(-3975 2075);
DISPLAY 0.787234 (-3975 2075);
PAINT MONO (-3975 2075);
DISPLAY INVISIBLE (-3975 2075);
FORCEADD OFFPAGE..1
(-4000 1950);
FORCEPROP 2 LAST $XR1 48 
J 0
(-4341 1950);
DISPLAY 0.638298 (-4341 1950);
PAINT MONO (-4341 1950);
FORCEPROP 2 LAST $XR0 25 
J 0
(-4251 1950);
DISPLAY 0.638298 (-4251 1950);
PAINT MONO (-4251 1950);
FORCEPROP 2 LAST CDS_LIB mstr_standard
J 0
(-4000 1950);
DISPLAY 0.787234 (-4000 1950);
PAINT MONO (-4000 1950);
DISPLAY INVISIBLE (-4000 1950);
FORCEPROP 1 LAST OFFPAGE TRUE
J 0
(-3675 1825);
DISPLAY 0.936170 (-3675 1825);
PAINT GREEN (-3675 1825);
DISPLAY INVISIBLE (-3675 1825);
FORCEPROP 1 LAST COMMENT_BODY TRUE
J 0
(-3875 1850);
DISPLAY 0.936170 (-3875 1850);
PAINT GREEN (-3875 1850);
DISPLAY INVISIBLE (-3875 1850);
FORCEPROP 2 LAST PATH I149
J 0
(-3950 2025);
DISPLAY 0.787234 (-3950 2025);
PAINT MONO (-3950 2025);
DISPLAY INVISIBLE (-3950 2025);
FORCEADD TAP..6
R 2
(900 4750);
FORCEPROP 3 LASTPIN (850 4750) SIG_NAME M_C_DQS_DN<13>
J 0
(860 4760);
DISPLAY 0.659574 (860 4760);
PAINT MONO (860 4760);
DISPLAY INVISIBLE (860 4760);
FORCEPROP 1 LASTPIN (850 4750) BN 13
J 2
(900 4760);
DISPLAY 0.617021 (900 4760);
PAINT PINK (900 4760);
FORCEPROP 2 LAST CDS_LIB mstr_standard
J 0
(900 4750);
DISPLAY 0.787234 (900 4750);
PAINT MONO (900 4750);
DISPLAY INVISIBLE (900 4750);
FORCEPROP 1 LAST BODY_TYPE PLUMBING
J 2
(900 4700);
DISPLAY 1.234043 (900 4700);
PAINT GREEN (900 4700);
DISPLAY INVISIBLE (900 4700);
FORCEPROP 1 LAST HDL_TAP TRUE
J 2
(575 4625);
DISPLAY 1.234043 (575 4625);
PAINT GREEN (575 4625);
DISPLAY INVISIBLE (575 4625);
FORCEPROP 1 LAST PATH I15
J 2
(900 4750);
DISPLAY 0.936170 (900 4750);
PAINT GREEN (900 4750);
DISPLAY INVISIBLE (900 4750);
FORCEADD OFFPAGE..6
(-3800 2650);
FORCEPROP 2 LAST $XR1 48 
J 0
(-4139 2650);
DISPLAY 0.638298 (-4139 2650);
PAINT MONO (-4139 2650);
FORCEPROP 2 LAST $XR0 25 
J 0
(-4049 2650);
DISPLAY 0.638298 (-4049 2650);
PAINT MONO (-4049 2650);
FORCEPROP 2 LAST CDS_LIB mstr_standard
J 0
(-3800 2650);
DISPLAY 0.787234 (-3800 2650);
PAINT MONO (-3800 2650);
DISPLAY INVISIBLE (-3800 2650);
FORCEPROP 1 LAST OFFPAGE TRUE
J 0
(-3475 2525);
DISPLAY 0.936170 (-3475 2525);
PAINT GREEN (-3475 2525);
DISPLAY INVISIBLE (-3475 2525);
FORCEPROP 1 LAST COMMENT_BODY TRUE
J 0
(-3700 2575);
DISPLAY 0.936170 (-3700 2575);
PAINT GREEN (-3700 2575);
DISPLAY INVISIBLE (-3700 2575);
FORCEPROP 2 LAST PATH I150
J 0
(-3750 2725);
DISPLAY 0.787234 (-3750 2725);
PAINT MONO (-3750 2725);
DISPLAY INVISIBLE (-3750 2725);
FORCEADD OFFPAGE..1
(-4800 1500);
FORCEPROP 2 LAST $XR1 48 
J 0
(-5141 1500);
DISPLAY 0.638298 (-5141 1500);
PAINT MONO (-5141 1500);
FORCEPROP 2 LAST $XR0 98 
J 0
(-5051 1500);
DISPLAY 0.638298 (-5051 1500);
PAINT MONO (-5051 1500);
FORCEPROP 2 LAST CDS_LIB mstr_standard
J 0
(-4800 1500);
DISPLAY 0.787234 (-4800 1500);
PAINT MONO (-4800 1500);
DISPLAY INVISIBLE (-4800 1500);
FORCEPROP 1 LAST OFFPAGE TRUE
J 0
(-4475 1375);
DISPLAY 0.936170 (-4475 1375);
PAINT GREEN (-4475 1375);
DISPLAY INVISIBLE (-4475 1375);
FORCEPROP 1 LAST COMMENT_BODY TRUE
J 0
(-4675 1400);
DISPLAY 0.936170 (-4675 1400);
PAINT GREEN (-4675 1400);
DISPLAY INVISIBLE (-4675 1400);
FORCEPROP 2 LAST PATH I151
J 0
(-4750 1575);
DISPLAY 0.787234 (-4750 1575);
PAINT MONO (-4750 1575);
DISPLAY INVISIBLE (-4750 1575);
FORCEADD TAP..6
(-3200 2700);
FORCEPROP 3 LASTPIN (-3150 2700) SIG_NAME M_C_ODT<0>
J 0
(-3140 2710);
DISPLAY 0.659574 (-3140 2710);
PAINT MONO (-3140 2710);
DISPLAY INVISIBLE (-3140 2710);
FORCEPROP 1 LASTPIN (-3150 2700) BN 0
J 0
(-3200 2710);
DISPLAY 0.617021 (-3200 2710);
PAINT PINK (-3200 2710);
FORCEPROP 2 LAST CDS_LIB mstr_standard
J 0
(-3200 2700);
DISPLAY 0.787234 (-3200 2700);
PAINT MONO (-3200 2700);
DISPLAY INVISIBLE (-3200 2700);
FORCEPROP 1 LAST BODY_TYPE PLUMBING
J 0
(-3200 2650);
DISPLAY 1.234043 (-3200 2650);
PAINT GREEN (-3200 2650);
DISPLAY INVISIBLE (-3200 2650);
FORCEPROP 1 LAST HDL_TAP TRUE
J 0
(-2875 2575);
DISPLAY 1.234043 (-2875 2575);
PAINT GREEN (-2875 2575);
DISPLAY INVISIBLE (-2875 2575);
FORCEPROP 1 LAST PATH I152
J 0
(-3200 2700);
DISPLAY 0.936170 (-3200 2700);
PAINT GREEN (-3200 2700);
DISPLAY INVISIBLE (-3200 2700);
FORCEADD TAP..6
(-3200 2750);
FORCEPROP 3 LASTPIN (-3150 2750) SIG_NAME M_C_ODT<1>
J 0
(-3140 2760);
DISPLAY 0.659574 (-3140 2760);
PAINT MONO (-3140 2760);
DISPLAY INVISIBLE (-3140 2760);
FORCEPROP 1 LASTPIN (-3150 2750) BN 1
J 0
(-3200 2760);
DISPLAY 0.617021 (-3200 2760);
PAINT PINK (-3200 2760);
FORCEPROP 2 LAST CDS_LIB mstr_standard
J 0
(-3200 2750);
DISPLAY 0.787234 (-3200 2750);
PAINT MONO (-3200 2750);
DISPLAY INVISIBLE (-3200 2750);
FORCEPROP 1 LAST BODY_TYPE PLUMBING
J 0
(-3200 2700);
DISPLAY 1.234043 (-3200 2700);
PAINT GREEN (-3200 2700);
DISPLAY INVISIBLE (-3200 2700);
FORCEPROP 1 LAST HDL_TAP TRUE
J 0
(-2875 2625);
DISPLAY 1.234043 (-2875 2625);
PAINT GREEN (-2875 2625);
DISPLAY INVISIBLE (-2875 2625);
FORCEPROP 1 LAST PATH I153
J 0
(-3200 2750);
DISPLAY 0.936170 (-3200 2750);
PAINT GREEN (-3200 2750);
DISPLAY INVISIBLE (-3200 2750);
FORCEADD OFFPAGE..1
(-3800 2850);
FORCEPROP 2 LAST $XR1 48 
J 0
(-4141 2850);
DISPLAY 0.638298 (-4141 2850);
PAINT MONO (-4141 2850);
FORCEPROP 2 LAST $XR0 25 
J 0
(-4051 2850);
DISPLAY 0.638298 (-4051 2850);
PAINT MONO (-4051 2850);
FORCEPROP 2 LAST CDS_LIB mstr_standard
J 0
(-3800 2850);
DISPLAY 0.787234 (-3800 2850);
PAINT MONO (-3800 2850);
DISPLAY INVISIBLE (-3800 2850);
FORCEPROP 1 LAST OFFPAGE TRUE
J 0
(-3475 2725);
DISPLAY 0.936170 (-3475 2725);
PAINT GREEN (-3475 2725);
DISPLAY INVISIBLE (-3475 2725);
FORCEPROP 1 LAST COMMENT_BODY TRUE
J 0
(-3675 2750);
DISPLAY 0.936170 (-3675 2750);
PAINT GREEN (-3675 2750);
DISPLAY INVISIBLE (-3675 2750);
FORCEPROP 2 LAST PATH I154
J 0
(-3750 2925);
DISPLAY 0.787234 (-3750 2925);
PAINT MONO (-3750 2925);
DISPLAY INVISIBLE (-3750 2925);
FORCEADD TAP..6
(-3200 2900);
FORCEPROP 3 LASTPIN (-3150 2900) SIG_NAME M_C_CKE<1>
J 0
(-3140 2910);
DISPLAY 0.659574 (-3140 2910);
PAINT MONO (-3140 2910);
DISPLAY INVISIBLE (-3140 2910);
FORCEPROP 1 LASTPIN (-3150 2900) BN 1
J 0
(-3200 2910);
DISPLAY 0.617021 (-3200 2910);
PAINT PINK (-3200 2910);
FORCEPROP 2 LAST CDS_LIB mstr_standard
J 0
(-3200 2900);
DISPLAY 0.787234 (-3200 2900);
PAINT MONO (-3200 2900);
DISPLAY INVISIBLE (-3200 2900);
FORCEPROP 1 LAST BODY_TYPE PLUMBING
J 0
(-3200 2850);
DISPLAY 1.234043 (-3200 2850);
PAINT GREEN (-3200 2850);
DISPLAY INVISIBLE (-3200 2850);
FORCEPROP 1 LAST HDL_TAP TRUE
J 0
(-2875 2775);
DISPLAY 1.234043 (-2875 2775);
PAINT GREEN (-2875 2775);
DISPLAY INVISIBLE (-2875 2775);
FORCEPROP 1 LAST PATH I155
J 0
(-3200 2900);
DISPLAY 0.936170 (-3200 2900);
PAINT GREEN (-3200 2900);
DISPLAY INVISIBLE (-3200 2900);
FORCEADD TAP..6
(-3200 2850);
FORCEPROP 3 LASTPIN (-3150 2850) SIG_NAME M_C_CKE<0>
J 0
(-3140 2860);
DISPLAY 0.659574 (-3140 2860);
PAINT MONO (-3140 2860);
DISPLAY INVISIBLE (-3140 2860);
FORCEPROP 1 LASTPIN (-3150 2850) BN 0
J 0
(-3200 2860);
DISPLAY 0.617021 (-3200 2860);
PAINT PINK (-3200 2860);
FORCEPROP 2 LAST CDS_LIB mstr_standard
J 0
(-3200 2850);
DISPLAY 0.787234 (-3200 2850);
PAINT MONO (-3200 2850);
DISPLAY INVISIBLE (-3200 2850);
FORCEPROP 1 LAST BODY_TYPE PLUMBING
J 0
(-3200 2800);
DISPLAY 1.234043 (-3200 2800);
PAINT GREEN (-3200 2800);
DISPLAY INVISIBLE (-3200 2800);
FORCEPROP 1 LAST HDL_TAP TRUE
J 0
(-2875 2725);
DISPLAY 1.234043 (-2875 2725);
PAINT GREEN (-2875 2725);
DISPLAY INVISIBLE (-2875 2725);
FORCEPROP 1 LAST PATH I156
J 0
(-3200 2850);
DISPLAY 0.936170 (-3200 2850);
PAINT GREEN (-3200 2850);
DISPLAY INVISIBLE (-3200 2850);
FORCEADD OFFPAGE..1
(-3800 2950);
FORCEPROP 2 LAST $XR1 48 
J 0
(-4141 2950);
DISPLAY 0.638298 (-4141 2950);
PAINT MONO (-4141 2950);
FORCEPROP 2 LAST $XR0 25 
J 0
(-4051 2950);
DISPLAY 0.638298 (-4051 2950);
PAINT MONO (-4051 2950);
FORCEPROP 2 LAST CDS_LIB mstr_standard
J 0
(-3800 2950);
DISPLAY 0.787234 (-3800 2950);
PAINT MONO (-3800 2950);
DISPLAY INVISIBLE (-3800 2950);
FORCEPROP 1 LAST OFFPAGE TRUE
J 0
(-3475 2825);
DISPLAY 0.936170 (-3475 2825);
PAINT GREEN (-3475 2825);
DISPLAY INVISIBLE (-3475 2825);
FORCEPROP 1 LAST COMMENT_BODY TRUE
J 0
(-3675 2850);
DISPLAY 0.936170 (-3675 2850);
PAINT GREEN (-3675 2850);
DISPLAY INVISIBLE (-3675 2850);
FORCEPROP 2 LAST PATH I157
J 0
(-3750 3025);
DISPLAY 0.787234 (-3750 3025);
PAINT MONO (-3750 3025);
DISPLAY INVISIBLE (-3750 3025);
FORCEADD TAP..6
(-3200 3150);
FORCEPROP 3 LASTPIN (-3150 3150) SIG_NAME M_C_CS_N<3>
J 0
(-3140 3160);
DISPLAY 0.659574 (-3140 3160);
PAINT MONO (-3140 3160);
DISPLAY INVISIBLE (-3140 3160);
FORCEPROP 1 LASTPIN (-3150 3150) BN 3
J 0
(-3200 3160);
DISPLAY 0.617021 (-3200 3160);
PAINT PINK (-3200 3160);
FORCEPROP 2 LAST CDS_LIB mstr_standard
J 0
(-3200 3150);
DISPLAY 0.787234 (-3200 3150);
PAINT MONO (-3200 3150);
DISPLAY INVISIBLE (-3200 3150);
FORCEPROP 1 LAST BODY_TYPE PLUMBING
J 0
(-3200 3100);
DISPLAY 1.234043 (-3200 3100);
PAINT GREEN (-3200 3100);
DISPLAY INVISIBLE (-3200 3100);
FORCEPROP 1 LAST HDL_TAP TRUE
J 0
(-2875 3025);
DISPLAY 1.234043 (-2875 3025);
PAINT GREEN (-2875 3025);
DISPLAY INVISIBLE (-2875 3025);
FORCEPROP 1 LAST PATH I158
J 0
(-3200 3150);
DISPLAY 0.936170 (-3200 3150);
PAINT GREEN (-3200 3150);
DISPLAY INVISIBLE (-3200 3150);
FORCEADD OFFPAGE..1
(-3800 3200);
FORCEPROP 2 LAST $XR1 48 
J 0
(-4141 3200);
DISPLAY 0.638298 (-4141 3200);
PAINT MONO (-4141 3200);
FORCEPROP 2 LAST $XR0 25 
J 0
(-4051 3200);
DISPLAY 0.638298 (-4051 3200);
PAINT MONO (-4051 3200);
FORCEPROP 2 LAST CDS_LIB mstr_standard
J 0
(-3800 3200);
DISPLAY 0.787234 (-3800 3200);
PAINT MONO (-3800 3200);
DISPLAY INVISIBLE (-3800 3200);
FORCEPROP 1 LAST OFFPAGE TRUE
J 0
(-3475 3075);
DISPLAY 0.936170 (-3475 3075);
PAINT GREEN (-3475 3075);
DISPLAY INVISIBLE (-3475 3075);
FORCEPROP 1 LAST COMMENT_BODY TRUE
J 0
(-3675 3100);
DISPLAY 0.936170 (-3675 3100);
PAINT GREEN (-3675 3100);
DISPLAY INVISIBLE (-3675 3100);
FORCEPROP 2 LAST PATH I159
J 0
(-3750 3275);
DISPLAY 0.787234 (-3750 3275);
PAINT MONO (-3750 3275);
DISPLAY INVISIBLE (-3750 3275);
FORCEADD TAP..6
R 2
(700 4800);
FORCEPROP 3 LASTPIN (650 4800) SIG_NAME M_C_DQS_DP<13>
J 0
(660 4810);
DISPLAY 0.659574 (660 4810);
PAINT MONO (660 4810);
DISPLAY INVISIBLE (660 4810);
FORCEPROP 1 LASTPIN (650 4800) BN 13
J 2
(700 4810);
DISPLAY 0.617021 (700 4810);
PAINT PINK (700 4810);
FORCEPROP 2 LAST CDS_LIB mstr_standard
J 0
(700 4800);
DISPLAY 0.787234 (700 4800);
PAINT MONO (700 4800);
DISPLAY INVISIBLE (700 4800);
FORCEPROP 1 LAST BODY_TYPE PLUMBING
J 2
(700 4750);
DISPLAY 1.234043 (700 4750);
PAINT GREEN (700 4750);
DISPLAY INVISIBLE (700 4750);
FORCEPROP 1 LAST HDL_TAP TRUE
J 2
(375 4675);
DISPLAY 1.234043 (375 4675);
PAINT GREEN (375 4675);
DISPLAY INVISIBLE (375 4675);
FORCEPROP 1 LAST PATH I16
J 2
(700 4800);
DISPLAY 0.936170 (700 4800);
PAINT GREEN (700 4800);
DISPLAY INVISIBLE (700 4800);
FORCEADD TAP..6
(-3200 3100);
FORCEPROP 3 LASTPIN (-3150 3100) SIG_NAME M_C_CS_N<2>
J 0
(-3140 3110);
DISPLAY 0.659574 (-3140 3110);
PAINT MONO (-3140 3110);
DISPLAY INVISIBLE (-3140 3110);
FORCEPROP 1 LASTPIN (-3150 3100) BN 2
J 0
(-3200 3110);
DISPLAY 0.617021 (-3200 3110);
PAINT PINK (-3200 3110);
FORCEPROP 2 LAST CDS_LIB mstr_standard
J 0
(-3200 3100);
DISPLAY 0.787234 (-3200 3100);
PAINT MONO (-3200 3100);
DISPLAY INVISIBLE (-3200 3100);
FORCEPROP 1 LAST BODY_TYPE PLUMBING
J 0
(-3200 3050);
DISPLAY 1.234043 (-3200 3050);
PAINT GREEN (-3200 3050);
DISPLAY INVISIBLE (-3200 3050);
FORCEPROP 1 LAST HDL_TAP TRUE
J 0
(-2875 2975);
DISPLAY 1.234043 (-2875 2975);
PAINT GREEN (-2875 2975);
DISPLAY INVISIBLE (-2875 2975);
FORCEPROP 1 LAST PATH I160
J 0
(-3200 3100);
DISPLAY 0.936170 (-3200 3100);
PAINT GREEN (-3200 3100);
DISPLAY INVISIBLE (-3200 3100);
FORCEADD TAP..6
(-3200 3050);
FORCEPROP 3 LASTPIN (-3150 3050) SIG_NAME M_C_CS_N<1>
J 0
(-3140 3060);
DISPLAY 0.659574 (-3140 3060);
PAINT MONO (-3140 3060);
DISPLAY INVISIBLE (-3140 3060);
FORCEPROP 1 LASTPIN (-3150 3050) BN 1
J 0
(-3200 3060);
DISPLAY 0.617021 (-3200 3060);
PAINT PINK (-3200 3060);
FORCEPROP 2 LAST CDS_LIB mstr_standard
J 0
(-3200 3050);
DISPLAY 0.787234 (-3200 3050);
PAINT MONO (-3200 3050);
DISPLAY INVISIBLE (-3200 3050);
FORCEPROP 1 LAST BODY_TYPE PLUMBING
J 0
(-3200 3000);
DISPLAY 1.234043 (-3200 3000);
PAINT GREEN (-3200 3000);
DISPLAY INVISIBLE (-3200 3000);
FORCEPROP 1 LAST HDL_TAP TRUE
J 0
(-2875 2925);
DISPLAY 1.234043 (-2875 2925);
PAINT GREEN (-2875 2925);
DISPLAY INVISIBLE (-2875 2925);
FORCEPROP 1 LAST PATH I161
J 0
(-3200 3050);
DISPLAY 0.936170 (-3200 3050);
PAINT GREEN (-3200 3050);
DISPLAY INVISIBLE (-3200 3050);
FORCEADD TAP..6
(-3200 3000);
FORCEPROP 3 LASTPIN (-3150 3000) SIG_NAME M_C_CS_N<0>
J 0
(-3140 3010);
DISPLAY 0.659574 (-3140 3010);
PAINT MONO (-3140 3010);
DISPLAY INVISIBLE (-3140 3010);
FORCEPROP 1 LASTPIN (-3150 3000) BN 0
J 0
(-3200 3010);
DISPLAY 0.617021 (-3200 3010);
PAINT PINK (-3200 3010);
FORCEPROP 2 LAST CDS_LIB mstr_standard
J 0
(-3200 3000);
DISPLAY 0.787234 (-3200 3000);
PAINT MONO (-3200 3000);
DISPLAY INVISIBLE (-3200 3000);
FORCEPROP 1 LAST BODY_TYPE PLUMBING
J 0
(-3200 2950);
DISPLAY 1.234043 (-3200 2950);
PAINT GREEN (-3200 2950);
DISPLAY INVISIBLE (-3200 2950);
FORCEPROP 1 LAST HDL_TAP TRUE
J 0
(-2875 2875);
DISPLAY 1.234043 (-2875 2875);
PAINT GREEN (-2875 2875);
DISPLAY INVISIBLE (-2875 2875);
FORCEPROP 1 LAST PATH I162
J 0
(-3200 3000);
DISPLAY 0.936170 (-3200 3000);
PAINT GREEN (-3200 3000);
DISPLAY INVISIBLE (-3200 3000);
FORCEADD TAP..6
R 2
(700 4700);
FORCEPROP 3 LASTPIN (650 4700) SIG_NAME M_C_DQS_DP<12>
J 0
(660 4710);
DISPLAY 0.659574 (660 4710);
PAINT MONO (660 4710);
DISPLAY INVISIBLE (660 4710);
FORCEPROP 1 LASTPIN (650 4700) BN 12
J 2
(700 4710);
DISPLAY 0.617021 (700 4710);
PAINT PINK (700 4710);
FORCEPROP 2 LAST CDS_LIB mstr_standard
J 0
(700 4700);
DISPLAY 0.787234 (700 4700);
PAINT MONO (700 4700);
DISPLAY INVISIBLE (700 4700);
FORCEPROP 1 LAST BODY_TYPE PLUMBING
J 2
(700 4650);
DISPLAY 1.234043 (700 4650);
PAINT GREEN (700 4650);
DISPLAY INVISIBLE (700 4650);
FORCEPROP 1 LAST HDL_TAP TRUE
J 2
(375 4575);
DISPLAY 1.234043 (375 4575);
PAINT GREEN (375 4575);
DISPLAY INVISIBLE (375 4575);
FORCEPROP 1 LAST PATH I17
J 2
(700 4700);
DISPLAY 0.936170 (700 4700);
PAINT GREEN (700 4700);
DISPLAY INVISIBLE (700 4700);
FORCEADD TAP..6
(-3750 3300);
FORCEPROP 3 LASTPIN (-3700 3300) SIG_NAME M_C_CLK_DN<0>
J 0
(-3690 3310);
DISPLAY 0.659574 (-3690 3310);
PAINT MONO (-3690 3310);
DISPLAY INVISIBLE (-3690 3310);
FORCEPROP 1 LASTPIN (-3700 3300) BN 0
J 0
(-3750 3310);
DISPLAY 0.617021 (-3750 3310);
PAINT PINK (-3750 3310);
FORCEPROP 2 LAST CDS_LIB mstr_standard
J 0
(-3750 3300);
DISPLAY 0.787234 (-3750 3300);
PAINT MONO (-3750 3300);
DISPLAY INVISIBLE (-3750 3300);
FORCEPROP 1 LAST BODY_TYPE PLUMBING
J 0
(-3750 3250);
DISPLAY 1.234043 (-3750 3250);
PAINT GREEN (-3750 3250);
DISPLAY INVISIBLE (-3750 3250);
FORCEPROP 1 LAST HDL_TAP TRUE
J 0
(-3425 3175);
DISPLAY 1.234043 (-3425 3175);
PAINT GREEN (-3425 3175);
DISPLAY INVISIBLE (-3425 3175);
FORCEPROP 1 LAST PATH I174
J 0
(-3750 3300);
DISPLAY 0.936170 (-3750 3300);
PAINT GREEN (-3750 3300);
DISPLAY INVISIBLE (-3750 3300);
FORCEADD TAP..6
(-3600 3350);
FORCEPROP 3 LASTPIN (-3550 3350) SIG_NAME M_C_CLK_DP<0>
J 0
(-3540 3360);
DISPLAY 0.659574 (-3540 3360);
PAINT MONO (-3540 3360);
DISPLAY INVISIBLE (-3540 3360);
FORCEPROP 1 LASTPIN (-3550 3350) BN 0
J 0
(-3600 3360);
DISPLAY 0.617021 (-3600 3360);
PAINT PINK (-3600 3360);
FORCEPROP 2 LAST CDS_LIB mstr_standard
J 0
(-3600 3350);
DISPLAY 0.787234 (-3600 3350);
PAINT MONO (-3600 3350);
DISPLAY INVISIBLE (-3600 3350);
FORCEPROP 1 LAST BODY_TYPE PLUMBING
J 0
(-3600 3300);
DISPLAY 1.234043 (-3600 3300);
PAINT GREEN (-3600 3300);
DISPLAY INVISIBLE (-3600 3300);
FORCEPROP 1 LAST HDL_TAP TRUE
J 0
(-3275 3225);
DISPLAY 1.234043 (-3275 3225);
PAINT GREEN (-3275 3225);
DISPLAY INVISIBLE (-3275 3225);
FORCEPROP 1 LAST PATH I175
J 0
(-3600 3350);
DISPLAY 0.936170 (-3600 3350);
PAINT GREEN (-3600 3350);
DISPLAY INVISIBLE (-3600 3350);
FORCEADD OFFPAGE..1
(-4300 3500);
FORCEPROP 2 LAST $XR1 48 
J 0
(-4611 3500);
DISPLAY 0.638298 (-4611 3500);
PAINT MONO (-4611 3500);
FORCEPROP 2 LAST $XR0 25 
J 0
(-4521 3500);
DISPLAY 0.638298 (-4521 3500);
PAINT MONO (-4521 3500);
FORCEPROP 2 LAST CDS_LIB mstr_standard
J 0
(-4300 3500);
DISPLAY 0.787234 (-4300 3500);
PAINT MONO (-4300 3500);
DISPLAY INVISIBLE (-4300 3500);
FORCEPROP 1 LAST OFFPAGE TRUE
J 0
(-3975 3375);
DISPLAY 0.936170 (-3975 3375);
PAINT GREEN (-3975 3375);
DISPLAY INVISIBLE (-3975 3375);
FORCEPROP 1 LAST COMMENT_BODY TRUE
J 0
(-4175 3400);
DISPLAY 0.936170 (-4175 3400);
PAINT GREEN (-4175 3400);
DISPLAY INVISIBLE (-4175 3400);
FORCEPROP 2 LAST PATH I177
J 0
(-4250 3575);
DISPLAY 0.787234 (-4250 3575);
PAINT MONO (-4250 3575);
DISPLAY INVISIBLE (-4250 3575);
FORCEADD OFFPAGE..1
(-4300 3550);
FORCEPROP 2 LAST $XR1 48 
J 0
(-4611 3550);
DISPLAY 0.638298 (-4611 3550);
PAINT MONO (-4611 3550);
FORCEPROP 2 LAST $XR0 25 
J 0
(-4521 3550);
DISPLAY 0.638298 (-4521 3550);
PAINT MONO (-4521 3550);
FORCEPROP 2 LAST CDS_LIB mstr_standard
J 0
(-4300 3550);
DISPLAY 0.787234 (-4300 3550);
PAINT MONO (-4300 3550);
DISPLAY INVISIBLE (-4300 3550);
FORCEPROP 1 LAST OFFPAGE TRUE
J 0
(-3975 3425);
DISPLAY 0.936170 (-3975 3425);
PAINT GREEN (-3975 3425);
DISPLAY INVISIBLE (-3975 3425);
FORCEPROP 1 LAST COMMENT_BODY TRUE
J 0
(-4175 3450);
DISPLAY 0.936170 (-4175 3450);
PAINT GREEN (-4175 3450);
DISPLAY INVISIBLE (-4175 3450);
FORCEPROP 2 LAST PATH I178
J 0
(-4250 3625);
DISPLAY 0.787234 (-4250 3625);
PAINT MONO (-4250 3625);
DISPLAY INVISIBLE (-4250 3625);
FORCEADD SCONN288_H44441004..4
(0 2050);
FORCEPROP 1 LAST LOCATION J4G3
J 0
(-450 3150);
DISPLAY 0.617021 (-450 3150);
PAINT AQUA (-450 3150);
FORCEPROP 1 LAST PART_NUMBER H44441-004
J 0
(-450 1000);
DISPLAY 0.617021 (-450 1000);
PAINT BLUE (-450 1000);
FORCEPROP 1 LAST MATERIAL SCONN
J 0
(-450 3100);
DISPLAY 0.617021 (-450 3100);
PAINT SKYBLUE (-450 3100);
FORCEPROP 2 LASTPIN (-500 2600) $PN 77
J 2
(-510 2610);
DISPLAY 0.617021 (-510 2610);
PAINT ORANGE (-510 2610);
FORCEPROP 2 LASTPIN (-500 2550) $PN 221
J 2
(-510 2560);
DISPLAY 0.617021 (-510 2560);
PAINT ORANGE (-510 2560);
FORCEPROP 2 LASTPIN (-500 2900) $PN 142
J 2
(-510 2910);
DISPLAY 0.617021 (-510 2910);
PAINT ORANGE (-510 2910);
FORCEPROP 2 LASTPIN (-500 2850) $PN 143
J 2
(-510 2860);
DISPLAY 0.617021 (-510 2860);
PAINT ORANGE (-510 2860);
FORCEPROP 2 LASTPIN (-500 2800) $PN 288
J 2
(-510 2810);
DISPLAY 0.617021 (-510 2810);
PAINT ORANGE (-510 2810);
FORCEPROP 2 LASTPIN (-500 2750) $PN 286
J 2
(-510 2760);
DISPLAY 0.617021 (-510 2760);
PAINT ORANGE (-510 2760);
FORCEPROP 2 LASTPIN (-500 2700) $PN 287
J 2
(-510 2710);
DISPLAY 0.617021 (-510 2710);
PAINT ORANGE (-510 2710);
FORCEPROP 2 LASTPIN (-500 2450) $PN 59
J 2
(-510 2460);
DISPLAY 0.617021 (-510 2460);
PAINT ORANGE (-510 2460);
FORCEPROP 2 LASTPIN (-500 2400) $PN 61
J 2
(-510 2410);
DISPLAY 0.617021 (-510 2410);
PAINT ORANGE (-510 2410);
FORCEPROP 2 LASTPIN (-500 2350) $PN 64
J 2
(-510 2360);
DISPLAY 0.617021 (-510 2360);
PAINT ORANGE (-510 2360);
FORCEPROP 2 LASTPIN (-500 2300) $PN 67
J 2
(-510 2310);
DISPLAY 0.617021 (-510 2310);
PAINT ORANGE (-510 2310);
FORCEPROP 2 LASTPIN (-500 2250) $PN 70
J 2
(-510 2260);
DISPLAY 0.617021 (-510 2260);
PAINT ORANGE (-510 2260);
FORCEPROP 2 LASTPIN (-500 2200) $PN 73
J 2
(-510 2210);
DISPLAY 0.617021 (-510 2210);
PAINT ORANGE (-510 2210);
FORCEPROP 2 LASTPIN (-500 2150) $PN 76
J 2
(-510 2160);
DISPLAY 0.617021 (-510 2160);
PAINT ORANGE (-510 2160);
FORCEPROP 2 LASTPIN (-500 2100) $PN 80
J 2
(-510 2110);
DISPLAY 0.617021 (-510 2110);
PAINT ORANGE (-510 2110);
FORCEPROP 2 LASTPIN (-500 2050) $PN 83
J 2
(-510 2060);
DISPLAY 0.617021 (-510 2060);
PAINT ORANGE (-510 2060);
FORCEPROP 2 LASTPIN (-500 2000) $PN 85
J 2
(-510 2010);
DISPLAY 0.617021 (-510 2010);
PAINT ORANGE (-510 2010);
FORCEPROP 2 LASTPIN (-500 1950) $PN 88
J 2
(-510 1960);
DISPLAY 0.617021 (-510 1960);
PAINT ORANGE (-510 1960);
FORCEPROP 2 LASTPIN (-500 1900) $PN 90
J 2
(-510 1910);
DISPLAY 0.617021 (-510 1910);
PAINT ORANGE (-510 1910);
FORCEPROP 2 LASTPIN (-500 1850) $PN 92
J 2
(-510 1860);
DISPLAY 0.617021 (-510 1860);
PAINT ORANGE (-510 1860);
FORCEPROP 2 LASTPIN (-500 1800) $PN 204
J 2
(-510 1810);
DISPLAY 0.617021 (-510 1810);
PAINT ORANGE (-510 1810);
FORCEPROP 2 LASTPIN (-500 1750) $PN 206
J 2
(-510 1760);
DISPLAY 0.617021 (-510 1760);
PAINT ORANGE (-510 1760);
FORCEPROP 2 LASTPIN (-500 1700) $PN 209
J 2
(-510 1710);
DISPLAY 0.617021 (-510 1710);
PAINT ORANGE (-510 1710);
FORCEPROP 2 LASTPIN (-500 1650) $PN 212
J 2
(-510 1660);
DISPLAY 0.617021 (-510 1660);
PAINT ORANGE (-510 1660);
FORCEPROP 2 LASTPIN (-500 1600) $PN 215
J 2
(-510 1610);
DISPLAY 0.617021 (-510 1610);
PAINT ORANGE (-510 1610);
FORCEPROP 2 LASTPIN (-500 1550) $PN 217
J 2
(-510 1560);
DISPLAY 0.617021 (-510 1560);
PAINT ORANGE (-510 1560);
FORCEPROP 2 LASTPIN (-500 1500) $PN 220
J 2
(-510 1510);
DISPLAY 0.617021 (-510 1510);
PAINT ORANGE (-510 1510);
FORCEPROP 2 LASTPIN (-500 1450) $PN 223
J 2
(-510 1460);
DISPLAY 0.617021 (-510 1460);
PAINT ORANGE (-510 1460);
FORCEPROP 2 LASTPIN (-500 1400) $PN 226
J 2
(-510 1410);
DISPLAY 0.617021 (-510 1410);
PAINT ORANGE (-510 1410);
FORCEPROP 2 LASTPIN (-500 1350) $PN 229
J 2
(-510 1360);
DISPLAY 0.617021 (-510 1360);
PAINT ORANGE (-510 1360);
FORCEPROP 2 LASTPIN (-500 1300) $PN 231
J 2
(-510 1310);
DISPLAY 0.617021 (-510 1310);
PAINT ORANGE (-510 1310);
FORCEPROP 2 LASTPIN (-500 1250) $PN 233
J 2
(-510 1260);
DISPLAY 0.617021 (-510 1260);
PAINT ORANGE (-510 1260);
FORCEPROP 2 LASTPIN (-500 1200) $PN 236
J 2
(-510 1210);
DISPLAY 0.617021 (-510 1210);
PAINT ORANGE (-510 1210);
FORCEPROP 2 LASTPIN (500 2900) $PN 1
J 0
(510 2910);
DISPLAY 0.617021 (510 2910);
PAINT ORANGE (510 2910);
FORCEPROP 2 LASTPIN (500 2850) $PN 145
J 0
(510 2860);
DISPLAY 0.617021 (510 2860);
PAINT ORANGE (510 2860);
FORCEPROP 1 LAST PACK_TYPE PIP
J 0
(-450 3200);
PAINT SKYBLUE (-450 3200);
DISPLAY INVISIBLE (-450 3200);
FORCEPROP 2 LAST BOM_COST MEM
J 0
(0 2050);
PAINT ORANGE (0 2050);
DISPLAY INVISIBLE (0 2050);
FORCEPROP 2 LAST CDS_LIB mstr_sconn
J 0
(0 2050);
PAINT ORANGE (0 2050);
DISPLAY INVISIBLE (0 2050);
FORCEPROP 2 LAST SEC_TYPE PIP
J 0
(-450 3200);
DISPLAY 1.021277 (-450 3200);
PAINT ORANGE (-450 3200);
DISPLAY INVISIBLE (-450 3200);
FORCEPROP 2 LAST SEC 4
J 0
(-450 3200);
DISPLAY 0.680851 (-450 3200);
PAINT MONO (-450 3200);
DISPLAY INVISIBLE (-450 3200);
FORCEPROP 2 LAST CDS_LOCATION J4G3
J 0
(-450 3150);
DISPLAY 0.617021 (-450 3150);
PAINT AQUA (-450 3150);
DISPLAY INVISIBLE (-450 3150);
FORCEPROP 1 LAST PATH I179
J 0
(0 3100);
PAINT GREEN (0 3100);
DISPLAY INVISIBLE (0 3100);
FORCEPROP 2 LAST ROOM DDR4_CH_C
J 0
(-450 3250);
PAINT ORANGE (-450 3250);
DISPLAY INVISIBLE (-450 3250);
FORCEADD TAP..6
R 2
(700 4600);
FORCEPROP 3 LASTPIN (650 4600) SIG_NAME M_C_DQS_DP<11>
J 0
(660 4610);
DISPLAY 0.659574 (660 4610);
PAINT MONO (660 4610);
DISPLAY INVISIBLE (660 4610);
FORCEPROP 1 LASTPIN (650 4600) BN 11
J 2
(700 4610);
DISPLAY 0.617021 (700 4610);
PAINT PINK (700 4610);
FORCEPROP 2 LAST CDS_LIB mstr_standard
J 0
(700 4600);
DISPLAY 0.787234 (700 4600);
PAINT MONO (700 4600);
DISPLAY INVISIBLE (700 4600);
FORCEPROP 1 LAST BODY_TYPE PLUMBING
J 2
(700 4550);
DISPLAY 1.234043 (700 4550);
PAINT GREEN (700 4550);
DISPLAY INVISIBLE (700 4550);
FORCEPROP 1 LAST HDL_TAP TRUE
J 2
(375 4475);
DISPLAY 1.234043 (375 4475);
PAINT GREEN (375 4475);
DISPLAY INVISIBLE (375 4475);
FORCEPROP 1 LAST PATH I18
J 2
(700 4600);
DISPLAY 0.936170 (700 4600);
PAINT GREEN (700 4600);
DISPLAY INVISIBLE (700 4600);
FORCEADD GND..1
R 2
(2500 1350);
FORCEPROP 3 LASTPIN (2500 1400) SIG_NAME GND\g
J 0
(2510 1410);
DISPLAY 0.659574 (2510 1410);
PAINT MONO (2510 1410);
DISPLAY INVISIBLE (2510 1410);
FORCEPROP 1 LAST VOLTAGE 0
J 0
(2500 1350);
PAINT SKYBLUE (2500 1350);
DISPLAY INVISIBLE (2500 1350);
FORCEPROP 1 LAST SIZE 1B
J 2
(2425 1300);
DISPLAY 1.170213 (2425 1300);
PAINT GREEN (2425 1300);
DISPLAY INVISIBLE (2425 1300);
FORCEPROP 2 LAST CDS_LIB mstr_symbols
J 0
(2500 1350);
DISPLAY 0.787234 (2500 1350);
PAINT MONO (2500 1350);
DISPLAY INVISIBLE (2500 1350);
FORCEPROP 2 LAST BOM_COST MEM
J 0
(2500 1355);
PAINT ORANGE (2500 1355);
DISPLAY INVISIBLE (2500 1355);
FORCEPROP 1 LAST BODY_TYPE PLUMBING
J 2
(2545 1307);
DISPLAY 0.340426 (2545 1307);
PAINT GREEN (2545 1307);
DISPLAY INVISIBLE (2545 1307);
FORCEPROP 1 LAST PATH I180
J 2
(2425 1350);
DISPLAY 1.404255 (2425 1350);
PAINT GREEN (2425 1350);
DISPLAY INVISIBLE (2425 1350);
FORCEPROP 2 LAST ROOM DDR4_CH_A
J 0
(2500 1355);
PAINT ORANGE (2500 1355);
DISPLAY INVISIBLE (2500 1355);
FORCEPROP 1 LAST HDL_POWER GND
J 2
(2500 1500);
DISPLAY 0.553191 (2500 1500);
PAINT GREEN (2500 1500);
DISPLAY INVISIBLE (2500 1500);
FORCEADD OFFPAGE..5
(-4175 2300);
FORCEPROP 2 LAST $XR23 94 
J 0
(-4789 2336);
DISPLAY 0.638298 (-4789 2336);
PAINT MONO (-4789 2336);
FORCEPROP 2 LAST $XR22 88 
J 0
(-4699 2336);
DISPLAY 0.638298 (-4699 2336);
PAINT MONO (-4699 2336);
FORCEPROP 2 LAST $XR21 87 
J 0
(-4609 2336);
DISPLAY 0.638298 (-4609 2336);
PAINT MONO (-4609 2336);
FORCEPROP 2 LAST $XR20 86 
J 0
(-4519 2336);
DISPLAY 0.638298 (-4519 2336);
PAINT MONO (-4519 2336);
FORCEPROP 2 LAST $XR19 85 
J 0
(-4429 2336);
DISPLAY 0.638298 (-4429 2336);
PAINT MONO (-4429 2336);
FORCEPROP 2 LAST $XR18 84 
J 0
(-5149 2264);
DISPLAY 0.638298 (-5149 2264);
PAINT MONO (-5149 2264);
FORCEPROP 2 LAST $XR17 83 
J 0
(-5059 2264);
DISPLAY 0.638298 (-5059 2264);
PAINT MONO (-5059 2264);
FORCEPROP 2 LAST $XR16 82 
J 0
(-4969 2264);
DISPLAY 0.638298 (-4969 2264);
PAINT MONO (-4969 2264);
FORCEPROP 2 LAST $XR15 81 
J 0
(-4879 2264);
DISPLAY 0.638298 (-4879 2264);
PAINT MONO (-4879 2264);
FORCEPROP 2 LAST $XR14 80 
J 0
(-4789 2264);
DISPLAY 0.638298 (-4789 2264);
PAINT MONO (-4789 2264);
FORCEPROP 2 LAST $XR13 79 
J 0
(-4699 2264);
DISPLAY 0.638298 (-4699 2264);
PAINT MONO (-4699 2264);
FORCEPROP 2 LAST $XR12 78 
J 0
(-4609 2264);
DISPLAY 0.638298 (-4609 2264);
PAINT MONO (-4609 2264);
FORCEPROP 2 LAST $XR11 77 
J 0
(-4519 2264);
DISPLAY 0.638298 (-4519 2264);
PAINT MONO (-4519 2264);
FORCEPROP 2 LAST $XR10 54 
J 0
(-4429 2264);
DISPLAY 0.638298 (-4429 2264);
PAINT MONO (-4429 2264);
FORCEPROP 2 LAST $XR9 53 
J 0
(-5239 2300);
DISPLAY 0.638298 (-5239 2300);
PAINT MONO (-5239 2300);
FORCEPROP 2 LAST $XR8 52 
J 0
(-5149 2300);
DISPLAY 0.638298 (-5149 2300);
PAINT MONO (-5149 2300);
FORCEPROP 2 LAST $XR7 51 
J 0
(-5059 2300);
DISPLAY 0.638298 (-5059 2300);
PAINT MONO (-5059 2300);
FORCEPROP 2 LAST $XR6 50 
J 0
(-4969 2300);
DISPLAY 0.638298 (-4969 2300);
PAINT MONO (-4969 2300);
FORCEPROP 2 LAST $XR5 49 
J 0
(-4879 2300);
DISPLAY 0.638298 (-4879 2300);
PAINT MONO (-4879 2300);
FORCEPROP 2 LAST $XR4 48 
J 0
(-4789 2300);
DISPLAY 0.638298 (-4789 2300);
PAINT MONO (-4789 2300);
FORCEPROP 2 LAST $XR3 46 
J 0
(-4699 2300);
DISPLAY 0.638298 (-4699 2300);
PAINT MONO (-4699 2300);
FORCEPROP 2 LAST $XR2 45 
J 0
(-4609 2300);
DISPLAY 0.638298 (-4609 2300);
PAINT MONO (-4609 2300);
FORCEPROP 2 LAST $XR1 44 
J 0
(-4519 2300);
DISPLAY 0.638298 (-4519 2300);
PAINT MONO (-4519 2300);
FORCEPROP 2 LAST $XR0 43 
J 0
(-4429 2300);
DISPLAY 0.638298 (-4429 2300);
PAINT MONO (-4429 2300);
FORCEPROP 2 LAST CDS_LIB mstr_standard
J 0
(-4175 2300);
DISPLAY 0.787234 (-4175 2300);
PAINT MONO (-4175 2300);
DISPLAY INVISIBLE (-4175 2300);
FORCEPROP 1 LAST OFFPAGE TRUE
J 0
(-3850 2175);
DISPLAY 1.404255 (-3850 2175);
PAINT GREEN (-3850 2175);
DISPLAY INVISIBLE (-3850 2175);
FORCEPROP 1 LAST COMMENT_BODY TRUE
J 0
(-4075 2225);
DISPLAY 1.404255 (-4075 2225);
PAINT GREEN (-4075 2225);
DISPLAY INVISIBLE (-4075 2225);
FORCEPROP 2 LAST PATH I183
J 0
(-4125 2375);
DISPLAY 0.787234 (-4125 2375);
PAINT ORANGE (-4125 2375);
DISPLAY INVISIBLE (-4125 2375);
FORCEADD GND..1
R 2
(-4950 1650);
FORCEPROP 3 LASTPIN (-4950 1700) SIG_NAME GND\g
J 0
(-4940 1710);
DISPLAY 0.659574 (-4940 1710);
PAINT MONO (-4940 1710);
DISPLAY INVISIBLE (-4940 1710);
FORCEPROP 1 LAST VOLTAGE 0
J 0
(-4950 1650);
PAINT SKYBLUE (-4950 1650);
DISPLAY INVISIBLE (-4950 1650);
FORCEPROP 2 LAST BOM_COST MEM
J 0
(-4950 1655);
PAINT ORANGE (-4950 1655);
DISPLAY INVISIBLE (-4950 1655);
FORCEPROP 2 LAST CDS_LIB mstr_symbols
J 0
(-4950 1650);
DISPLAY 0.787234 (-4950 1650);
PAINT MONO (-4950 1650);
DISPLAY INVISIBLE (-4950 1650);
FORCEPROP 1 LAST SIZE 1B
J 2
(-5025 1600);
DISPLAY 1.170213 (-5025 1600);
PAINT GREEN (-5025 1600);
DISPLAY INVISIBLE (-5025 1600);
FORCEPROP 1 LAST BODY_TYPE PLUMBING
J 2
(-4905 1607);
DISPLAY 0.340426 (-4905 1607);
PAINT GREEN (-4905 1607);
DISPLAY INVISIBLE (-4905 1607);
FORCEPROP 1 LAST PATH I184
J 2
(-5025 1650);
DISPLAY 1.404255 (-5025 1650);
PAINT GREEN (-5025 1650);
DISPLAY INVISIBLE (-5025 1650);
FORCEPROP 2 LAST ROOM DDR4_CH_A
J 0
(-4950 1655);
PAINT ORANGE (-4950 1655);
DISPLAY INVISIBLE (-4950 1655);
FORCEPROP 1 LAST HDL_POWER GND
J 2
(-4950 1800);
DISPLAY 0.553191 (-4950 1800);
PAINT GREEN (-4950 1800);
DISPLAY INVISIBLE (-4950 1800);
FORCEADD OFFPAGE..1
(-3800 1600);
FORCEPROP 2 LAST $XR5 48 
J 0
(-4501 1600);
DISPLAY 0.638298 (-4501 1600);
PAINT MONO (-4501 1600);
FORCEPROP 2 LAST $XR4 46 
J 0
(-4411 1600);
DISPLAY 0.638298 (-4411 1600);
PAINT MONO (-4411 1600);
FORCEPROP 2 LAST $XR3 45 
J 0
(-4321 1600);
DISPLAY 0.638298 (-4321 1600);
PAINT MONO (-4321 1600);
FORCEPROP 2 LAST $XR2 44 
J 0
(-4231 1600);
DISPLAY 0.638298 (-4231 1600);
PAINT MONO (-4231 1600);
FORCEPROP 2 LAST $XR1 43 
J 0
(-4141 1600);
DISPLAY 0.638298 (-4141 1600);
PAINT MONO (-4141 1600);
FORCEPROP 2 LAST $XR0 99 
J 0
(-4051 1600);
DISPLAY 0.638298 (-4051 1600);
PAINT MONO (-4051 1600);
FORCEPROP 2 LAST CDS_LIB mstr_standard
J 0
(-3800 1600);
DISPLAY 0.787234 (-3800 1600);
PAINT MONO (-3800 1600);
DISPLAY INVISIBLE (-3800 1600);
FORCEPROP 1 LAST OFFPAGE TRUE
J 0
(-3475 1475);
DISPLAY 0.936170 (-3475 1475);
PAINT GREEN (-3475 1475);
DISPLAY INVISIBLE (-3475 1475);
FORCEPROP 1 LAST COMMENT_BODY TRUE
J 0
(-3675 1500);
DISPLAY 0.936170 (-3675 1500);
PAINT GREEN (-3675 1500);
DISPLAY INVISIBLE (-3675 1500);
FORCEPROP 2 LAST PATH I186
J 0
(-4075 1650);
DISPLAY 0.787234 (-4075 1650);
PAINT ORANGE (-4075 1650);
DISPLAY INVISIBLE (-4075 1650);
FORCEADD OFFPAGE..6
(-3800 1650);
FORCEPROP 2 LASTPIN (-3750 1650) SIG_NAME SMB_DDR_ABC_VPP_SDA
J 0
(-3710 1660);
DISPLAY 0.617021 (-3710 1660);
PAINT ORANGE (-3710 1660);
FORCEPROP 2 LAST $XR5 99 
J 0
(-4499 1650);
DISPLAY 0.638298 (-4499 1650);
PAINT MONO (-4499 1650);
FORCEPROP 2 LAST $XR4 48 
J 0
(-4409 1650);
DISPLAY 0.638298 (-4409 1650);
PAINT MONO (-4409 1650);
FORCEPROP 2 LAST $XR3 46 
J 0
(-4319 1650);
DISPLAY 0.638298 (-4319 1650);
PAINT MONO (-4319 1650);
FORCEPROP 2 LAST $XR2 45 
J 0
(-4229 1650);
DISPLAY 0.638298 (-4229 1650);
PAINT MONO (-4229 1650);
FORCEPROP 2 LAST $XR1 44 
J 0
(-4139 1650);
DISPLAY 0.638298 (-4139 1650);
PAINT MONO (-4139 1650);
FORCEPROP 2 LAST $XR0 43 
J 0
(-4049 1650);
DISPLAY 0.638298 (-4049 1650);
PAINT MONO (-4049 1650);
FORCEPROP 2 LAST CDS_LIB mstr_standard
J 0
(-3800 1650);
DISPLAY 0.787234 (-3800 1650);
PAINT MONO (-3800 1650);
DISPLAY INVISIBLE (-3800 1650);
FORCEPROP 1 LAST OFFPAGE TRUE
J 0
(-3475 1525);
DISPLAY 0.936170 (-3475 1525);
PAINT GREEN (-3475 1525);
DISPLAY INVISIBLE (-3475 1525);
FORCEPROP 1 LAST COMMENT_BODY TRUE
J 0
(-3700 1575);
DISPLAY 0.936170 (-3700 1575);
PAINT GREEN (-3700 1575);
DISPLAY INVISIBLE (-3700 1575);
FORCEPROP 2 LAST PATH I187
J 0
(-4100 1700);
DISPLAY 0.787234 (-4100 1700);
PAINT ORANGE (-4100 1700);
DISPLAY INVISIBLE (-4100 1700);
FORCEADD CAP_A..1
R 2
(-4650 1300);
FORCEPROP 1 LAST LOCATION C4G19
J 2
(-4700 1400);
DISPLAY 0.617021 (-4700 1400);
PAINT AQUA (-4700 1400);
FORCEPROP 1 LAST PART_NUMBER A36096-045
J 2
(-4700 1150);
DISPLAY 0.617021 (-4700 1150);
PAINT BLUE (-4700 1150);
FORCEPROP 1 LAST VALUE 0.01UF
J 2
(-4700 1350);
DISPLAY 0.617021 (-4700 1350);
PAINT SKYBLUE (-4700 1350);
FORCEPROP 1 LAST TOLERANCE 10%
J 2
(-4700 1250);
DISPLAY 0.617021 (-4700 1250);
PAINT SKYBLUE (-4700 1250);
FORCEPROP 1 LAST PACK_TYPE 0402V
J 2
(-4700 1100);
DISPLAY 0.617021 (-4700 1100);
PAINT SKYBLUE (-4700 1100);
FORCEPROP 1 LAST VOLTAGE 25V
J 2
(-4700 1300);
DISPLAY 0.617021 (-4700 1300);
PAINT SKYBLUE (-4700 1300);
FORCEPROP 1 LAST MATERIAL X7R
J 2
(-4700 1200);
DISPLAY 0.617021 (-4700 1200);
PAINT SKYBLUE (-4700 1200);
FORCEPROP 1 LASTPIN (-4650 1400) $PN 1
J 2
(-4660 1380);
DISPLAY 0.617021 (-4660 1380);
PAINT ORANGE (-4660 1380);
FORCEPROP 1 LASTPIN (-4650 1200) $PN 2
J 2
(-4660 1180);
DISPLAY 0.617021 (-4660 1180);
PAINT ORANGE (-4660 1180);
FORCEPROP 2 LAST CDS_LOCATION C4G19
J 2
(-4700 1400);
DISPLAY 0.617021 (-4700 1400);
PAINT AQUA (-4700 1400);
DISPLAY INVISIBLE (-4700 1400);
FORCEPROP 2 LAST BOM_COST MEM
J 0
(-4650 1300);
PAINT ORANGE (-4650 1300);
DISPLAY INVISIBLE (-4650 1300);
FORCEPROP 2 LAST CDS_LIB dev_discrete
J 0
(-4650 1300);
PAINT ORANGE (-4650 1300);
DISPLAY INVISIBLE (-4650 1300);
FORCEPROP 2 LAST CDS_SEC 1
J 0
(-4700 1450);
PAINT ORANGE (-4700 1450);
DISPLAY INVISIBLE (-4700 1450);
FORCEPROP 2 LAST SEC_TYPE 0402V
J 0
(-4700 1500);
DISPLAY 1.021277 (-4700 1500);
PAINT ORANGE (-4700 1500);
DISPLAY INVISIBLE (-4700 1500);
FORCEPROP 2 LAST SEC 1
J 0
(-4700 1500);
PAINT MONO (-4700 1500);
DISPLAY INVISIBLE (-4700 1500);
FORCEPROP 1 LAST PATH I188
J 2
(-4700 1450);
DISPLAY 0.978723 (-4700 1450);
PAINT WHITE (-4700 1450);
DISPLAY INVISIBLE (-4700 1450);
FORCEPROP 2 LAST ROOM DDR4_CH_C
J 0
(-4650 1300);
PAINT ORANGE (-4650 1300);
DISPLAY INVISIBLE (-4650 1300);
FORCEADD GND..1
(-4650 1050);
FORCEPROP 3 LASTPIN (-4650 1100) SIG_NAME GND\g
J 0
(-4640 1110);
DISPLAY 0.659574 (-4640 1110);
PAINT MONO (-4640 1110);
DISPLAY INVISIBLE (-4640 1110);
FORCEPROP 1 LAST VOLTAGE 0
J 0
(-4650 1050);
PAINT SKYBLUE (-4650 1050);
DISPLAY INVISIBLE (-4650 1050);
FORCEPROP 2 LAST BOM_COST MEM
J 0
(-4650 1055);
PAINT ORANGE (-4650 1055);
DISPLAY INVISIBLE (-4650 1055);
FORCEPROP 2 LAST CDS_LIB mstr_symbols
J 0
(-4650 1050);
PAINT ORANGE (-4650 1050);
DISPLAY INVISIBLE (-4650 1050);
FORCEPROP 1 LAST SIZE 1B
J 0
(-4575 1000);
DISPLAY 1.787234 (-4575 1000);
PAINT GREEN (-4575 1000);
DISPLAY INVISIBLE (-4575 1000);
FORCEPROP 1 LAST BODY_TYPE PLUMBING
J 0
(-4695 1007);
DISPLAY 0.340426 (-4695 1007);
PAINT GREEN (-4695 1007);
DISPLAY INVISIBLE (-4695 1007);
FORCEPROP 1 LAST PATH I189
J 0
(-4575 1050);
DISPLAY 1.404255 (-4575 1050);
PAINT GREEN (-4575 1050);
DISPLAY INVISIBLE (-4575 1050);
FORCEPROP 2 LAST ROOM DDR4_CH_A
J 0
(-4650 1055);
PAINT ORANGE (-4650 1055);
DISPLAY INVISIBLE (-4650 1055);
FORCEPROP 1 LAST HDL_POWER GND
J 0
(-4650 1200);
DISPLAY 1.404255 (-4650 1200);
PAINT GREEN (-4650 1200);
DISPLAY INVISIBLE (-4650 1200);
FORCEADD TAP..6
R 2
(900 4450);
FORCEPROP 3 LASTPIN (850 4450) SIG_NAME M_C_DQS_DN<10>
J 0
(860 4460);
DISPLAY 0.659574 (860 4460);
PAINT MONO (860 4460);
DISPLAY INVISIBLE (860 4460);
FORCEPROP 1 LASTPIN (850 4450) BN 10
J 2
(900 4460);
DISPLAY 0.617021 (900 4460);
PAINT PINK (900 4460);
FORCEPROP 2 LAST CDS_LIB mstr_standard
J 0
(900 4450);
DISPLAY 0.787234 (900 4450);
PAINT MONO (900 4450);
DISPLAY INVISIBLE (900 4450);
FORCEPROP 1 LAST BODY_TYPE PLUMBING
J 2
(900 4400);
DISPLAY 1.234043 (900 4400);
PAINT GREEN (900 4400);
DISPLAY INVISIBLE (900 4400);
FORCEPROP 1 LAST HDL_TAP TRUE
J 2
(575 4325);
DISPLAY 1.234043 (575 4325);
PAINT GREEN (575 4325);
DISPLAY INVISIBLE (575 4325);
FORCEPROP 1 LAST PATH I19
J 2
(900 4450);
DISPLAY 0.936170 (900 4450);
PAINT GREEN (900 4450);
DISPLAY INVISIBLE (900 4450);
FORCEADD PVPP_ABC..1
(-700 3050);
FORCEPROP 3 LASTPIN (-700 3000) SIG_NAME PVPP_ABC\g
J 0
(-690 3010);
DISPLAY 0.659574 (-690 3010);
PAINT MONO (-690 3010);
DISPLAY INVISIBLE (-690 3010);
FORCEPROP 1 LAST VOLTAGE 2.5V
J 0
(-745 3007);
DISPLAY 0.340426 (-745 3007);
PAINT SKYBLUE (-745 3007);
DISPLAY INVISIBLE (-745 3007);
FORCEPROP 0 LAST BOM_COST MEM
J 0
(-700 3150);
PAINT ORANGE (-700 3150);
DISPLAY INVISIBLE (-700 3150);
FORCEPROP 2 LAST CDS_LIB mstr_symbols
J 0
(-700 3050);
PAINT ORANGE (-700 3050);
DISPLAY INVISIBLE (-700 3050);
FORCEPROP 1 LAST BODY_TYPE PLUMBING
J 0
(-745 3007);
DISPLAY 0.340426 (-745 3007);
PAINT GREEN (-745 3007);
DISPLAY INVISIBLE (-745 3007);
FORCEPROP 1 LAST PATH I190
J 0
(-650 3075);
DISPLAY 0.872340 (-650 3075);
PAINT AQUA (-650 3075);
DISPLAY INVISIBLE (-650 3075);
FORCEPROP 2 LAST ROOM DDR4_CH_A
J 0
(-700 3150);
PAINT ORANGE (-700 3150);
DISPLAY INVISIBLE (-700 3150);
FORCEPROP 1 LAST HDL_POWER PVPP_ABC
J 1
(-700 3100);
DISPLAY 0.872340 (-700 3100);
PAINT GREEN (-700 3100);
DISPLAY INVISIBLE (-700 3100);
FORCEADD PVPP_ABC..1
(-4950 2000);
FORCEPROP 3 LASTPIN (-4950 1950) SIG_NAME PVPP_ABC\g
J 0
(-4940 1960);
DISPLAY 0.659574 (-4940 1960);
PAINT MONO (-4940 1960);
DISPLAY INVISIBLE (-4940 1960);
FORCEPROP 1 LAST VOLTAGE 2.5V
J 0
(-4995 1957);
DISPLAY 0.340426 (-4995 1957);
PAINT SKYBLUE (-4995 1957);
DISPLAY INVISIBLE (-4995 1957);
FORCEPROP 0 LAST BOM_COST MEM
J 0
(-4950 2100);
PAINT ORANGE (-4950 2100);
DISPLAY INVISIBLE (-4950 2100);
FORCEPROP 2 LAST CDS_LIB mstr_symbols
J 0
(-4950 2000);
PAINT ORANGE (-4950 2000);
DISPLAY INVISIBLE (-4950 2000);
FORCEPROP 1 LAST BODY_TYPE PLUMBING
J 0
(-4995 1957);
DISPLAY 0.340426 (-4995 1957);
PAINT GREEN (-4995 1957);
DISPLAY INVISIBLE (-4995 1957);
FORCEPROP 1 LAST PATH I191
J 0
(-4900 2025);
DISPLAY 0.872340 (-4900 2025);
PAINT AQUA (-4900 2025);
DISPLAY INVISIBLE (-4900 2025);
FORCEPROP 2 LAST ROOM DDR4_CH_A
J 0
(-4950 2100);
PAINT ORANGE (-4950 2100);
DISPLAY INVISIBLE (-4950 2100);
FORCEPROP 1 LAST HDL_POWER PVPP_ABC
J 1
(-4950 2050);
DISPLAY 0.872340 (-4950 2050);
PAINT GREEN (-4950 2050);
DISPLAY INVISIBLE (-4950 2050);
FORCEADD OFFPAGE..1
(-3850 1200);
FORCEPROP 2 LAST $XR5 48 
J 0
(-4551 1200);
DISPLAY 0.638298 (-4551 1200);
PAINT MONO (-4551 1200);
FORCEPROP 2 LAST $XR4 46 
J 0
(-4461 1200);
DISPLAY 0.638298 (-4461 1200);
PAINT MONO (-4461 1200);
FORCEPROP 2 LAST $XR3 45 
J 0
(-4371 1200);
DISPLAY 0.638298 (-4371 1200);
PAINT MONO (-4371 1200);
FORCEPROP 2 LAST $XR2 44 
J 0
(-4281 1200);
DISPLAY 0.638298 (-4281 1200);
PAINT MONO (-4281 1200);
FORCEPROP 2 LAST $XR1 43 
J 0
(-4191 1200);
DISPLAY 0.638298 (-4191 1200);
PAINT MONO (-4191 1200);
FORCEPROP 2 LAST $XR0 89 
J 0
(-4101 1200);
DISPLAY 0.638298 (-4101 1200);
PAINT MONO (-4101 1200);
FORCEPROP 2 LAST CDS_LIB mstr_standard
J 0
(-3850 1200);
PAINT ORANGE (-3850 1200);
DISPLAY INVISIBLE (-3850 1200);
FORCEPROP 1 LAST OFFPAGE TRUE
J 0
(-3525 1075);
DISPLAY 0.936170 (-3525 1075);
PAINT GREEN (-3525 1075);
DISPLAY INVISIBLE (-3525 1075);
FORCEPROP 1 LAST COMMENT_BODY TRUE
J 0
(-3725 1100);
DISPLAY 0.936170 (-3725 1100);
PAINT GREEN (-3725 1100);
DISPLAY INVISIBLE (-3725 1100);
FORCEPROP 2 LAST PATH I192
J 0
(-3800 1275);
PAINT ORANGE (-3800 1275);
DISPLAY INVISIBLE (-3800 1275);
FORCEADD TAP..6
(-3600 3450);
FORCEPROP 3 LASTPIN (-3550 3450) SIG_NAME M_C_CLK_DP<1>
J 0
(-3540 3460);
DISPLAY 0.659574 (-3540 3460);
PAINT MONO (-3540 3460);
DISPLAY INVISIBLE (-3540 3460);
FORCEPROP 1 LASTPIN (-3550 3450) BN 1
J 0
(-3602 3458);
DISPLAY 0.617021 (-3602 3458);
PAINT PINK (-3602 3458);
FORCEPROP 2 LAST CDS_LIB mstr_standard
J 0
(-3600 3450);
PAINT MONO (-3600 3450);
DISPLAY INVISIBLE (-3600 3450);
FORCEPROP 1 LAST BODY_TYPE PLUMBING
J 0
(-3600 3400);
DISPLAY 1.234043 (-3600 3400);
PAINT GREEN (-3600 3400);
DISPLAY INVISIBLE (-3600 3400);
FORCEPROP 1 LAST HDL_TAP TRUE
J 0
(-3275 3325);
DISPLAY 1.234043 (-3275 3325);
PAINT GREEN (-3275 3325);
DISPLAY INVISIBLE (-3275 3325);
FORCEPROP 1 LAST PATH I196
J 0
(-3602 3450);
DISPLAY 0.872340 (-3602 3450);
PAINT GREEN (-3602 3450);
DISPLAY INVISIBLE (-3602 3450);
FORCEADD TAP..6
(-3750 3400);
FORCEPROP 3 LASTPIN (-3700 3400) SIG_NAME M_C_CLK_DN<1>
J 0
(-3690 3410);
DISPLAY 0.659574 (-3690 3410);
PAINT MONO (-3690 3410);
DISPLAY INVISIBLE (-3690 3410);
FORCEPROP 1 LASTPIN (-3700 3400) BN 1
J 0
(-3752 3408);
DISPLAY 0.617021 (-3752 3408);
PAINT PINK (-3752 3408);
FORCEPROP 2 LAST CDS_LIB mstr_standard
J 0
(-3750 3400);
PAINT MONO (-3750 3400);
DISPLAY INVISIBLE (-3750 3400);
FORCEPROP 1 LAST BODY_TYPE PLUMBING
J 0
(-3750 3350);
DISPLAY 1.234043 (-3750 3350);
PAINT GREEN (-3750 3350);
DISPLAY INVISIBLE (-3750 3350);
FORCEPROP 1 LAST HDL_TAP TRUE
J 0
(-3425 3275);
DISPLAY 1.234043 (-3425 3275);
PAINT GREEN (-3425 3275);
DISPLAY INVISIBLE (-3425 3275);
FORCEPROP 1 LAST PATH I197
J 0
(-3752 3400);
DISPLAY 0.872340 (-3752 3400);
PAINT GREEN (-3752 3400);
DISPLAY INVISIBLE (-3752 3400);
FORCEADD P12V_NVDIMM_ABC..1
(700 3125);
FORCEPROP 3 LASTPIN (700 3075) SIG_NAME P12V_NVDIMM_ABC\g
J 0
(710 3085);
DISPLAY 0.659574 (710 3085);
PAINT MONO (710 3085);
DISPLAY INVISIBLE (710 3085);
FORCEPROP 1 LAST VOLTAGE 12.0
J 0
(655 3082);
DISPLAY 0.340426 (655 3082);
PAINT SKYBLUE (655 3082);
DISPLAY INVISIBLE (655 3082);
FORCEPROP 2 LAST CDS_LIB mstr_symbols
J 0
(700 3125);
PAINT ORANGE (700 3125);
DISPLAY INVISIBLE (700 3125);
FORCEPROP 1 LAST BODY_TYPE PLUMBING
J 0
(655 3082);
DISPLAY 0.340426 (655 3082);
PAINT GREEN (655 3082);
DISPLAY INVISIBLE (655 3082);
FORCEPROP 1 LAST PATH I198
J 0
(750 3150);
DISPLAY 0.872340 (750 3150);
PAINT AQUA (750 3150);
DISPLAY INVISIBLE (750 3150);
FORCEPROP 1 LAST HDL_POWER P12V_NVDIMM_ABC
J 1
(700 3150);
DISPLAY 0.872340 (700 3150);
PAINT GREEN (700 3150);
DISPLAY INVISIBLE (700 3150);
FORCEADD OFFPAGE..3
(1600 5200);
FORCEPROP 2 LAST $XR1 48 
J 0
(1904 5200);
DISPLAY 0.638298 (1904 5200);
PAINT MONO (1904 5200);
FORCEPROP 2 LAST $XR0 25 
J 0
(1814 5200);
DISPLAY 0.638298 (1814 5200);
PAINT MONO (1814 5200);
FORCEPROP 2 LAST CDS_LIB mstr_standard
J 0
(1600 5200);
DISPLAY 0.787234 (1600 5200);
PAINT MONO (1600 5200);
DISPLAY INVISIBLE (1600 5200);
FORCEPROP 1 LAST OFFPAGE TRUE
J 0
(1925 5075);
DISPLAY 0.936170 (1925 5075);
PAINT GREEN (1925 5075);
DISPLAY INVISIBLE (1925 5075);
FORCEPROP 1 LAST COMMENT_BODY TRUE
J 0
(1550 5100);
DISPLAY 0.936170 (1550 5100);
PAINT GREEN (1550 5100);
DISPLAY INVISIBLE (1550 5100);
FORCEPROP 2 LAST PATH I2
J 0
(1800 5275);
DISPLAY 0.787234 (1800 5275);
PAINT MONO (1800 5275);
DISPLAY INVISIBLE (1800 5275);
FORCEADD TAP..6
R 2
(900 4550);
FORCEPROP 3 LASTPIN (850 4550) SIG_NAME M_C_DQS_DN<11>
J 0
(860 4560);
DISPLAY 0.659574 (860 4560);
PAINT MONO (860 4560);
DISPLAY INVISIBLE (860 4560);
FORCEPROP 1 LASTPIN (850 4550) BN 11
J 2
(900 4560);
DISPLAY 0.617021 (900 4560);
PAINT PINK (900 4560);
FORCEPROP 2 LAST CDS_LIB mstr_standard
J 0
(900 4550);
DISPLAY 0.787234 (900 4550);
PAINT MONO (900 4550);
DISPLAY INVISIBLE (900 4550);
FORCEPROP 1 LAST BODY_TYPE PLUMBING
J 2
(900 4500);
DISPLAY 1.234043 (900 4500);
PAINT GREEN (900 4500);
DISPLAY INVISIBLE (900 4500);
FORCEPROP 1 LAST HDL_TAP TRUE
J 2
(575 4425);
DISPLAY 1.234043 (575 4425);
PAINT GREEN (575 4425);
DISPLAY INVISIBLE (575 4425);
FORCEPROP 1 LAST PATH I20
J 2
(900 4550);
DISPLAY 0.936170 (900 4550);
PAINT GREEN (900 4550);
DISPLAY INVISIBLE (900 4550);
FORCEADD TAP..6
R 2
(900 4350);
FORCEPROP 3 LASTPIN (850 4350) SIG_NAME M_C_DQS_DN<9>
J 0
(860 4360);
DISPLAY 0.659574 (860 4360);
PAINT MONO (860 4360);
DISPLAY INVISIBLE (860 4360);
FORCEPROP 1 LASTPIN (850 4350) BN 9
J 2
(900 4360);
DISPLAY 0.617021 (900 4360);
PAINT PINK (900 4360);
FORCEPROP 2 LAST CDS_LIB mstr_standard
J 0
(900 4350);
DISPLAY 0.787234 (900 4350);
PAINT MONO (900 4350);
DISPLAY INVISIBLE (900 4350);
FORCEPROP 1 LAST BODY_TYPE PLUMBING
J 2
(900 4300);
DISPLAY 1.234043 (900 4300);
PAINT GREEN (900 4300);
DISPLAY INVISIBLE (900 4300);
FORCEPROP 1 LAST HDL_TAP TRUE
J 2
(575 4225);
DISPLAY 1.234043 (575 4225);
PAINT GREEN (575 4225);
DISPLAY INVISIBLE (575 4225);
FORCEPROP 1 LAST PATH I21
J 2
(900 4350);
DISPLAY 0.936170 (900 4350);
PAINT GREEN (900 4350);
DISPLAY INVISIBLE (900 4350);
FORCEADD TAP..6
R 2
(700 4500);
FORCEPROP 3 LASTPIN (650 4500) SIG_NAME M_C_DQS_DP<10>
J 0
(660 4510);
DISPLAY 0.659574 (660 4510);
PAINT MONO (660 4510);
DISPLAY INVISIBLE (660 4510);
FORCEPROP 1 LASTPIN (650 4500) BN 10
J 2
(700 4510);
DISPLAY 0.617021 (700 4510);
PAINT PINK (700 4510);
FORCEPROP 2 LAST CDS_LIB mstr_standard
J 0
(700 4500);
DISPLAY 0.787234 (700 4500);
PAINT MONO (700 4500);
DISPLAY INVISIBLE (700 4500);
FORCEPROP 1 LAST BODY_TYPE PLUMBING
J 2
(700 4450);
DISPLAY 1.234043 (700 4450);
PAINT GREEN (700 4450);
DISPLAY INVISIBLE (700 4450);
FORCEPROP 1 LAST HDL_TAP TRUE
J 2
(375 4375);
DISPLAY 1.234043 (375 4375);
PAINT GREEN (375 4375);
DISPLAY INVISIBLE (375 4375);
FORCEPROP 1 LAST PATH I22
J 2
(700 4500);
DISPLAY 0.936170 (700 4500);
PAINT GREEN (700 4500);
DISPLAY INVISIBLE (700 4500);
FORCEADD TAP..6
R 2
(700 4400);
FORCEPROP 3 LASTPIN (650 4400) SIG_NAME M_C_DQS_DP<9>
J 0
(660 4410);
DISPLAY 0.659574 (660 4410);
PAINT MONO (660 4410);
DISPLAY INVISIBLE (660 4410);
FORCEPROP 1 LASTPIN (650 4400) BN 9
J 2
(700 4410);
DISPLAY 0.617021 (700 4410);
PAINT PINK (700 4410);
FORCEPROP 2 LAST CDS_LIB mstr_standard
J 0
(700 4400);
DISPLAY 0.787234 (700 4400);
PAINT MONO (700 4400);
DISPLAY INVISIBLE (700 4400);
FORCEPROP 1 LAST BODY_TYPE PLUMBING
J 2
(700 4350);
DISPLAY 1.234043 (700 4350);
PAINT GREEN (700 4350);
DISPLAY INVISIBLE (700 4350);
FORCEPROP 1 LAST HDL_TAP TRUE
J 2
(375 4275);
DISPLAY 1.234043 (375 4275);
PAINT GREEN (375 4275);
DISPLAY INVISIBLE (375 4275);
FORCEPROP 1 LAST PATH I23
J 2
(700 4400);
DISPLAY 0.936170 (700 4400);
PAINT GREEN (700 4400);
DISPLAY INVISIBLE (700 4400);
FORCEADD TAP..6
R 2
(900 4150);
FORCEPROP 3 LASTPIN (850 4150) SIG_NAME M_C_DQS_DN<7>
J 0
(860 4160);
DISPLAY 0.659574 (860 4160);
PAINT MONO (860 4160);
DISPLAY INVISIBLE (860 4160);
FORCEPROP 1 LASTPIN (850 4150) BN 7
J 2
(900 4160);
DISPLAY 0.617021 (900 4160);
PAINT PINK (900 4160);
FORCEPROP 2 LAST CDS_LIB mstr_standard
J 0
(900 4150);
DISPLAY 0.787234 (900 4150);
PAINT MONO (900 4150);
DISPLAY INVISIBLE (900 4150);
FORCEPROP 1 LAST BODY_TYPE PLUMBING
J 2
(900 4100);
DISPLAY 1.234043 (900 4100);
PAINT GREEN (900 4100);
DISPLAY INVISIBLE (900 4100);
FORCEPROP 1 LAST HDL_TAP TRUE
J 2
(575 4025);
DISPLAY 1.234043 (575 4025);
PAINT GREEN (575 4025);
DISPLAY INVISIBLE (575 4025);
FORCEPROP 1 LAST PATH I24
J 2
(900 4150);
DISPLAY 0.936170 (900 4150);
PAINT GREEN (900 4150);
DISPLAY INVISIBLE (900 4150);
FORCEADD TAP..6
R 2
(900 4250);
FORCEPROP 3 LASTPIN (850 4250) SIG_NAME M_C_DQS_DN<8>
J 0
(860 4260);
DISPLAY 0.659574 (860 4260);
PAINT MONO (860 4260);
DISPLAY INVISIBLE (860 4260);
FORCEPROP 1 LASTPIN (850 4250) BN 8
J 2
(900 4260);
DISPLAY 0.617021 (900 4260);
PAINT PINK (900 4260);
FORCEPROP 2 LAST CDS_LIB mstr_standard
J 0
(900 4250);
DISPLAY 0.787234 (900 4250);
PAINT MONO (900 4250);
DISPLAY INVISIBLE (900 4250);
FORCEPROP 1 LAST BODY_TYPE PLUMBING
J 2
(900 4200);
DISPLAY 1.234043 (900 4200);
PAINT GREEN (900 4200);
DISPLAY INVISIBLE (900 4200);
FORCEPROP 1 LAST HDL_TAP TRUE
J 2
(575 4125);
DISPLAY 1.234043 (575 4125);
PAINT GREEN (575 4125);
DISPLAY INVISIBLE (575 4125);
FORCEPROP 1 LAST PATH I25
J 2
(900 4250);
DISPLAY 0.936170 (900 4250);
PAINT GREEN (900 4250);
DISPLAY INVISIBLE (900 4250);
FORCEADD TAP..6
R 2
(700 4300);
FORCEPROP 3 LASTPIN (650 4300) SIG_NAME M_C_DQS_DP<8>
J 0
(660 4310);
DISPLAY 0.659574 (660 4310);
PAINT MONO (660 4310);
DISPLAY INVISIBLE (660 4310);
FORCEPROP 1 LASTPIN (650 4300) BN 8
J 2
(700 4310);
DISPLAY 0.617021 (700 4310);
PAINT PINK (700 4310);
FORCEPROP 2 LAST CDS_LIB mstr_standard
J 0
(700 4300);
DISPLAY 0.787234 (700 4300);
PAINT MONO (700 4300);
DISPLAY INVISIBLE (700 4300);
FORCEPROP 1 LAST BODY_TYPE PLUMBING
J 2
(700 4250);
DISPLAY 1.234043 (700 4250);
PAINT GREEN (700 4250);
DISPLAY INVISIBLE (700 4250);
FORCEPROP 1 LAST HDL_TAP TRUE
J 2
(375 4175);
DISPLAY 1.234043 (375 4175);
PAINT GREEN (375 4175);
DISPLAY INVISIBLE (375 4175);
FORCEPROP 1 LAST PATH I26
J 2
(700 4300);
DISPLAY 0.936170 (700 4300);
PAINT GREEN (700 4300);
DISPLAY INVISIBLE (700 4300);
FORCEADD TAP..6
R 2
(700 4200);
FORCEPROP 3 LASTPIN (650 4200) SIG_NAME M_C_DQS_DP<7>
J 0
(660 4210);
DISPLAY 0.659574 (660 4210);
PAINT MONO (660 4210);
DISPLAY INVISIBLE (660 4210);
FORCEPROP 1 LASTPIN (650 4200) BN 7
J 2
(700 4210);
DISPLAY 0.617021 (700 4210);
PAINT PINK (700 4210);
FORCEPROP 2 LAST CDS_LIB mstr_standard
J 0
(700 4200);
DISPLAY 0.787234 (700 4200);
PAINT MONO (700 4200);
DISPLAY INVISIBLE (700 4200);
FORCEPROP 1 LAST BODY_TYPE PLUMBING
J 2
(700 4150);
DISPLAY 1.234043 (700 4150);
PAINT GREEN (700 4150);
DISPLAY INVISIBLE (700 4150);
FORCEPROP 1 LAST HDL_TAP TRUE
J 2
(375 4075);
DISPLAY 1.234043 (375 4075);
PAINT GREEN (375 4075);
DISPLAY INVISIBLE (375 4075);
FORCEPROP 1 LAST PATH I27
J 2
(700 4200);
DISPLAY 0.936170 (700 4200);
PAINT GREEN (700 4200);
DISPLAY INVISIBLE (700 4200);
FORCEADD TAP..6
R 2
(700 4100);
FORCEPROP 3 LASTPIN (650 4100) SIG_NAME M_C_DQS_DP<6>
J 0
(660 4110);
DISPLAY 0.659574 (660 4110);
PAINT MONO (660 4110);
DISPLAY INVISIBLE (660 4110);
FORCEPROP 1 LASTPIN (650 4100) BN 6
J 2
(700 4110);
DISPLAY 0.617021 (700 4110);
PAINT PINK (700 4110);
FORCEPROP 2 LAST CDS_LIB mstr_standard
J 0
(700 4100);
DISPLAY 0.787234 (700 4100);
PAINT MONO (700 4100);
DISPLAY INVISIBLE (700 4100);
FORCEPROP 1 LAST BODY_TYPE PLUMBING
J 2
(700 4050);
DISPLAY 1.234043 (700 4050);
PAINT GREEN (700 4050);
DISPLAY INVISIBLE (700 4050);
FORCEPROP 1 LAST HDL_TAP TRUE
J 2
(375 3975);
DISPLAY 1.234043 (375 3975);
PAINT GREEN (375 3975);
DISPLAY INVISIBLE (375 3975);
FORCEPROP 1 LAST PATH I28
J 2
(700 4100);
DISPLAY 0.936170 (700 4100);
PAINT GREEN (700 4100);
DISPLAY INVISIBLE (700 4100);
FORCEADD TAP..6
R 2
(900 3950);
FORCEPROP 3 LASTPIN (850 3950) SIG_NAME M_C_DQS_DN<5>
J 0
(860 3960);
DISPLAY 0.659574 (860 3960);
PAINT MONO (860 3960);
DISPLAY INVISIBLE (860 3960);
FORCEPROP 1 LASTPIN (850 3950) BN 5
J 2
(900 3960);
DISPLAY 0.617021 (900 3960);
PAINT PINK (900 3960);
FORCEPROP 2 LAST CDS_LIB mstr_standard
J 0
(900 3950);
DISPLAY 0.787234 (900 3950);
PAINT MONO (900 3950);
DISPLAY INVISIBLE (900 3950);
FORCEPROP 1 LAST BODY_TYPE PLUMBING
J 2
(900 3900);
DISPLAY 1.234043 (900 3900);
PAINT GREEN (900 3900);
DISPLAY INVISIBLE (900 3900);
FORCEPROP 1 LAST HDL_TAP TRUE
J 2
(575 3825);
DISPLAY 1.234043 (575 3825);
PAINT GREEN (575 3825);
DISPLAY INVISIBLE (575 3825);
FORCEPROP 1 LAST PATH I29
J 2
(900 3950);
DISPLAY 0.936170 (900 3950);
PAINT GREEN (900 3950);
DISPLAY INVISIBLE (900 3950);
FORCEADD TAP..6
R 2
(900 5150);
FORCEPROP 3 LASTPIN (850 5150) SIG_NAME M_C_DQS_DN<17>
J 0
(860 5160);
DISPLAY 0.659574 (860 5160);
PAINT MONO (860 5160);
DISPLAY INVISIBLE (860 5160);
FORCEPROP 1 LASTPIN (850 5150) BN 17
J 2
(900 5160);
DISPLAY 0.617021 (900 5160);
PAINT PINK (900 5160);
FORCEPROP 2 LAST CDS_LIB mstr_standard
J 2
(900 5150);
DISPLAY 0.787234 (900 5150);
PAINT MONO (900 5150);
DISPLAY INVISIBLE (900 5150);
FORCEPROP 1 LAST BODY_TYPE PLUMBING
J 2
(900 5100);
DISPLAY 1.234043 (900 5100);
PAINT GREEN (900 5100);
DISPLAY INVISIBLE (900 5100);
FORCEPROP 1 LAST HDL_TAP TRUE
J 2
(575 5025);
DISPLAY 1.234043 (575 5025);
PAINT GREEN (575 5025);
DISPLAY INVISIBLE (575 5025);
FORCEPROP 1 LAST PATH I3
J 2
(900 5150);
DISPLAY 0.936170 (900 5150);
PAINT GREEN (900 5150);
DISPLAY INVISIBLE (900 5150);
FORCEADD TAP..6
R 2
(900 4050);
FORCEPROP 3 LASTPIN (850 4050) SIG_NAME M_C_DQS_DN<6>
J 0
(860 4060);
DISPLAY 0.659574 (860 4060);
PAINT MONO (860 4060);
DISPLAY INVISIBLE (860 4060);
FORCEPROP 1 LASTPIN (850 4050) BN 6
J 2
(900 4060);
DISPLAY 0.617021 (900 4060);
PAINT PINK (900 4060);
FORCEPROP 2 LAST CDS_LIB mstr_standard
J 0
(900 4050);
DISPLAY 0.787234 (900 4050);
PAINT MONO (900 4050);
DISPLAY INVISIBLE (900 4050);
FORCEPROP 1 LAST BODY_TYPE PLUMBING
J 2
(900 4000);
DISPLAY 1.234043 (900 4000);
PAINT GREEN (900 4000);
DISPLAY INVISIBLE (900 4000);
FORCEPROP 1 LAST HDL_TAP TRUE
J 2
(575 3925);
DISPLAY 1.234043 (575 3925);
PAINT GREEN (575 3925);
DISPLAY INVISIBLE (575 3925);
FORCEPROP 1 LAST PATH I30
J 2
(900 4050);
DISPLAY 0.936170 (900 4050);
PAINT GREEN (900 4050);
DISPLAY INVISIBLE (900 4050);
FORCEADD TAP..6
R 2
(900 3850);
FORCEPROP 3 LASTPIN (850 3850) SIG_NAME M_C_DQS_DN<4>
J 0
(860 3860);
DISPLAY 0.659574 (860 3860);
PAINT MONO (860 3860);
DISPLAY INVISIBLE (860 3860);
FORCEPROP 1 LASTPIN (850 3850) BN 4
J 2
(900 3860);
DISPLAY 0.617021 (900 3860);
PAINT PINK (900 3860);
FORCEPROP 2 LAST CDS_LIB mstr_standard
J 0
(900 3850);
DISPLAY 0.787234 (900 3850);
PAINT MONO (900 3850);
DISPLAY INVISIBLE (900 3850);
FORCEPROP 1 LAST BODY_TYPE PLUMBING
J 2
(900 3800);
DISPLAY 1.234043 (900 3800);
PAINT GREEN (900 3800);
DISPLAY INVISIBLE (900 3800);
FORCEPROP 1 LAST HDL_TAP TRUE
J 2
(575 3725);
DISPLAY 1.234043 (575 3725);
PAINT GREEN (575 3725);
DISPLAY INVISIBLE (575 3725);
FORCEPROP 1 LAST PATH I31
J 2
(900 3850);
DISPLAY 0.936170 (900 3850);
PAINT GREEN (900 3850);
DISPLAY INVISIBLE (900 3850);
FORCEADD TAP..6
R 2
(700 4000);
FORCEPROP 3 LASTPIN (650 4000) SIG_NAME M_C_DQS_DP<5>
J 0
(660 4010);
DISPLAY 0.659574 (660 4010);
PAINT MONO (660 4010);
DISPLAY INVISIBLE (660 4010);
FORCEPROP 1 LASTPIN (650 4000) BN 5
J 2
(700 4010);
DISPLAY 0.617021 (700 4010);
PAINT PINK (700 4010);
FORCEPROP 2 LAST CDS_LIB mstr_standard
J 0
(700 4000);
DISPLAY 0.787234 (700 4000);
PAINT MONO (700 4000);
DISPLAY INVISIBLE (700 4000);
FORCEPROP 1 LAST BODY_TYPE PLUMBING
J 2
(700 3950);
DISPLAY 1.234043 (700 3950);
PAINT GREEN (700 3950);
DISPLAY INVISIBLE (700 3950);
FORCEPROP 1 LAST HDL_TAP TRUE
J 2
(375 3875);
DISPLAY 1.234043 (375 3875);
PAINT GREEN (375 3875);
DISPLAY INVISIBLE (375 3875);
FORCEPROP 1 LAST PATH I32
J 2
(700 4000);
DISPLAY 0.936170 (700 4000);
PAINT GREEN (700 4000);
DISPLAY INVISIBLE (700 4000);
FORCEADD TAP..6
R 2
(700 3900);
FORCEPROP 3 LASTPIN (650 3900) SIG_NAME M_C_DQS_DP<4>
J 0
(660 3910);
DISPLAY 0.659574 (660 3910);
PAINT MONO (660 3910);
DISPLAY INVISIBLE (660 3910);
FORCEPROP 1 LASTPIN (650 3900) BN 4
J 2
(700 3910);
DISPLAY 0.617021 (700 3910);
PAINT PINK (700 3910);
FORCEPROP 2 LAST CDS_LIB mstr_standard
J 0
(700 3900);
DISPLAY 0.787234 (700 3900);
PAINT MONO (700 3900);
DISPLAY INVISIBLE (700 3900);
FORCEPROP 1 LAST BODY_TYPE PLUMBING
J 2
(700 3850);
DISPLAY 1.234043 (700 3850);
PAINT GREEN (700 3850);
DISPLAY INVISIBLE (700 3850);
FORCEPROP 1 LAST HDL_TAP TRUE
J 2
(375 3775);
DISPLAY 1.234043 (375 3775);
PAINT GREEN (375 3775);
DISPLAY INVISIBLE (375 3775);
FORCEPROP 1 LAST PATH I33
J 2
(700 3900);
DISPLAY 0.936170 (700 3900);
PAINT GREEN (700 3900);
DISPLAY INVISIBLE (700 3900);
FORCEADD TAP..6
R 2
(700 3800);
FORCEPROP 3 LASTPIN (650 3800) SIG_NAME M_C_DQS_DP<3>
J 0
(660 3810);
DISPLAY 0.659574 (660 3810);
PAINT MONO (660 3810);
DISPLAY INVISIBLE (660 3810);
FORCEPROP 1 LASTPIN (650 3800) BN 3
J 2
(700 3810);
DISPLAY 0.617021 (700 3810);
PAINT PINK (700 3810);
FORCEPROP 2 LAST CDS_LIB mstr_standard
J 0
(700 3800);
DISPLAY 0.787234 (700 3800);
PAINT MONO (700 3800);
DISPLAY INVISIBLE (700 3800);
FORCEPROP 1 LAST BODY_TYPE PLUMBING
J 2
(700 3750);
DISPLAY 1.234043 (700 3750);
PAINT GREEN (700 3750);
DISPLAY INVISIBLE (700 3750);
FORCEPROP 1 LAST HDL_TAP TRUE
J 2
(375 3675);
DISPLAY 1.234043 (375 3675);
PAINT GREEN (375 3675);
DISPLAY INVISIBLE (375 3675);
FORCEPROP 1 LAST PATH I34
J 2
(700 3800);
DISPLAY 0.936170 (700 3800);
PAINT GREEN (700 3800);
DISPLAY INVISIBLE (700 3800);
FORCEADD TAP..6
R 2
(900 3550);
FORCEPROP 3 LASTPIN (850 3550) SIG_NAME M_C_DQS_DN<1>
J 0
(860 3560);
DISPLAY 0.659574 (860 3560);
PAINT MONO (860 3560);
DISPLAY INVISIBLE (860 3560);
FORCEPROP 1 LASTPIN (850 3550) BN 1
J 2
(900 3560);
DISPLAY 0.617021 (900 3560);
PAINT PINK (900 3560);
FORCEPROP 2 LAST CDS_LIB mstr_standard
J 0
(900 3550);
DISPLAY 0.787234 (900 3550);
PAINT MONO (900 3550);
DISPLAY INVISIBLE (900 3550);
FORCEPROP 1 LAST BODY_TYPE PLUMBING
J 2
(900 3500);
DISPLAY 1.234043 (900 3500);
PAINT GREEN (900 3500);
DISPLAY INVISIBLE (900 3500);
FORCEPROP 1 LAST HDL_TAP TRUE
J 2
(575 3425);
DISPLAY 1.234043 (575 3425);
PAINT GREEN (575 3425);
DISPLAY INVISIBLE (575 3425);
FORCEPROP 1 LAST PATH I35
J 2
(900 3550);
DISPLAY 0.936170 (900 3550);
PAINT GREEN (900 3550);
DISPLAY INVISIBLE (900 3550);
FORCEADD TAP..6
R 2
(900 3650);
FORCEPROP 3 LASTPIN (850 3650) SIG_NAME M_C_DQS_DN<2>
J 0
(860 3660);
DISPLAY 0.659574 (860 3660);
PAINT MONO (860 3660);
DISPLAY INVISIBLE (860 3660);
FORCEPROP 1 LASTPIN (850 3650) BN 2
J 2
(900 3660);
DISPLAY 0.617021 (900 3660);
PAINT PINK (900 3660);
FORCEPROP 2 LAST CDS_LIB mstr_standard
J 0
(900 3650);
DISPLAY 0.787234 (900 3650);
PAINT MONO (900 3650);
DISPLAY INVISIBLE (900 3650);
FORCEPROP 1 LAST BODY_TYPE PLUMBING
J 2
(900 3600);
DISPLAY 1.234043 (900 3600);
PAINT GREEN (900 3600);
DISPLAY INVISIBLE (900 3600);
FORCEPROP 1 LAST HDL_TAP TRUE
J 2
(575 3525);
DISPLAY 1.234043 (575 3525);
PAINT GREEN (575 3525);
DISPLAY INVISIBLE (575 3525);
FORCEPROP 1 LAST PATH I36
J 2
(900 3650);
DISPLAY 0.936170 (900 3650);
PAINT GREEN (900 3650);
DISPLAY INVISIBLE (900 3650);
FORCEADD TAP..6
R 2
(900 3750);
FORCEPROP 3 LASTPIN (850 3750) SIG_NAME M_C_DQS_DN<3>
J 0
(860 3760);
DISPLAY 0.659574 (860 3760);
PAINT MONO (860 3760);
DISPLAY INVISIBLE (860 3760);
FORCEPROP 1 LASTPIN (850 3750) BN 3
J 2
(900 3760);
DISPLAY 0.617021 (900 3760);
PAINT PINK (900 3760);
FORCEPROP 2 LAST CDS_LIB mstr_standard
J 0
(900 3750);
DISPLAY 0.787234 (900 3750);
PAINT MONO (900 3750);
DISPLAY INVISIBLE (900 3750);
FORCEPROP 1 LAST BODY_TYPE PLUMBING
J 2
(900 3700);
DISPLAY 1.234043 (900 3700);
PAINT GREEN (900 3700);
DISPLAY INVISIBLE (900 3700);
FORCEPROP 1 LAST HDL_TAP TRUE
J 2
(575 3625);
DISPLAY 1.234043 (575 3625);
PAINT GREEN (575 3625);
DISPLAY INVISIBLE (575 3625);
FORCEPROP 1 LAST PATH I37
J 2
(900 3750);
DISPLAY 0.936170 (900 3750);
PAINT GREEN (900 3750);
DISPLAY INVISIBLE (900 3750);
FORCEADD TAP..6
R 2
(700 3700);
FORCEPROP 3 LASTPIN (650 3700) SIG_NAME M_C_DQS_DP<2>
J 0
(660 3710);
DISPLAY 0.659574 (660 3710);
PAINT MONO (660 3710);
DISPLAY INVISIBLE (660 3710);
FORCEPROP 1 LASTPIN (650 3700) BN 2
J 2
(700 3710);
DISPLAY 0.617021 (700 3710);
PAINT PINK (700 3710);
FORCEPROP 2 LAST CDS_LIB mstr_standard
J 0
(700 3700);
DISPLAY 0.787234 (700 3700);
PAINT MONO (700 3700);
DISPLAY INVISIBLE (700 3700);
FORCEPROP 1 LAST BODY_TYPE PLUMBING
J 2
(700 3650);
DISPLAY 1.234043 (700 3650);
PAINT GREEN (700 3650);
DISPLAY INVISIBLE (700 3650);
FORCEPROP 1 LAST HDL_TAP TRUE
J 2
(375 3575);
DISPLAY 1.234043 (375 3575);
PAINT GREEN (375 3575);
DISPLAY INVISIBLE (375 3575);
FORCEPROP 1 LAST PATH I38
J 2
(700 3700);
DISPLAY 0.936170 (700 3700);
PAINT GREEN (700 3700);
DISPLAY INVISIBLE (700 3700);
FORCEADD TAP..6
R 2
(700 3600);
FORCEPROP 3 LASTPIN (650 3600) SIG_NAME M_C_DQS_DP<1>
J 0
(660 3610);
DISPLAY 0.659574 (660 3610);
PAINT MONO (660 3610);
DISPLAY INVISIBLE (660 3610);
FORCEPROP 1 LASTPIN (650 3600) BN 1
J 2
(700 3610);
DISPLAY 0.617021 (700 3610);
PAINT PINK (700 3610);
FORCEPROP 2 LAST CDS_LIB mstr_standard
J 0
(700 3600);
DISPLAY 0.787234 (700 3600);
PAINT MONO (700 3600);
DISPLAY INVISIBLE (700 3600);
FORCEPROP 1 LAST BODY_TYPE PLUMBING
J 2
(700 3550);
DISPLAY 1.234043 (700 3550);
PAINT GREEN (700 3550);
DISPLAY INVISIBLE (700 3550);
FORCEPROP 1 LAST HDL_TAP TRUE
J 2
(375 3475);
DISPLAY 1.234043 (375 3475);
PAINT GREEN (375 3475);
DISPLAY INVISIBLE (375 3475);
FORCEPROP 1 LAST PATH I39
J 2
(700 3600);
DISPLAY 0.936170 (700 3600);
PAINT GREEN (700 3600);
DISPLAY INVISIBLE (700 3600);
FORCEADD TAP..6
R 2
(700 5200);
FORCEPROP 3 LASTPIN (650 5200) SIG_NAME M_C_DQS_DP<17>
J 0
(660 5210);
DISPLAY 0.659574 (660 5210);
PAINT MONO (660 5210);
DISPLAY INVISIBLE (660 5210);
FORCEPROP 1 LASTPIN (650 5200) BN 17
J 2
(700 5210);
DISPLAY 0.617021 (700 5210);
PAINT PINK (700 5210);
FORCEPROP 2 LAST CDS_LIB mstr_standard
J 2
(700 5200);
DISPLAY 0.787234 (700 5200);
PAINT MONO (700 5200);
DISPLAY INVISIBLE (700 5200);
FORCEPROP 1 LAST BODY_TYPE PLUMBING
J 2
(700 5150);
DISPLAY 1.234043 (700 5150);
PAINT GREEN (700 5150);
DISPLAY INVISIBLE (700 5150);
FORCEPROP 1 LAST HDL_TAP TRUE
J 2
(375 5075);
DISPLAY 1.234043 (375 5075);
PAINT GREEN (375 5075);
DISPLAY INVISIBLE (375 5075);
FORCEPROP 1 LAST PATH I4
J 2
(700 5200);
DISPLAY 0.936170 (700 5200);
PAINT GREEN (700 5200);
DISPLAY INVISIBLE (700 5200);
FORCEADD TAP..6
R 2
(900 3450);
FORCEPROP 3 LASTPIN (850 3450) SIG_NAME M_C_DQS_DN<0>
J 0
(860 3460);
DISPLAY 0.659574 (860 3460);
PAINT MONO (860 3460);
DISPLAY INVISIBLE (860 3460);
FORCEPROP 1 LASTPIN (850 3450) BN 0
J 2
(900 3460);
DISPLAY 0.617021 (900 3460);
PAINT PINK (900 3460);
FORCEPROP 2 LAST CDS_LIB mstr_standard
J 0
(900 3450);
DISPLAY 0.787234 (900 3450);
PAINT MONO (900 3450);
DISPLAY INVISIBLE (900 3450);
FORCEPROP 1 LAST BODY_TYPE PLUMBING
J 2
(900 3400);
DISPLAY 1.234043 (900 3400);
PAINT GREEN (900 3400);
DISPLAY INVISIBLE (900 3400);
FORCEPROP 1 LAST HDL_TAP TRUE
J 2
(575 3325);
DISPLAY 1.234043 (575 3325);
PAINT GREEN (575 3325);
DISPLAY INVISIBLE (575 3325);
FORCEPROP 1 LAST PATH I40
J 2
(900 3450);
DISPLAY 0.936170 (900 3450);
PAINT GREEN (900 3450);
DISPLAY INVISIBLE (900 3450);
FORCEADD TAP..6
R 2
(700 3500);
FORCEPROP 3 LASTPIN (650 3500) SIG_NAME M_C_DQS_DP<0>
J 0
(660 3510);
DISPLAY 0.659574 (660 3510);
PAINT MONO (660 3510);
DISPLAY INVISIBLE (660 3510);
FORCEPROP 1 LASTPIN (650 3500) BN 0
J 2
(700 3510);
DISPLAY 0.617021 (700 3510);
PAINT PINK (700 3510);
FORCEPROP 2 LAST CDS_LIB mstr_standard
J 0
(700 3500);
DISPLAY 0.787234 (700 3500);
PAINT MONO (700 3500);
DISPLAY INVISIBLE (700 3500);
FORCEPROP 1 LAST BODY_TYPE PLUMBING
J 2
(700 3450);
DISPLAY 1.234043 (700 3450);
PAINT GREEN (700 3450);
DISPLAY INVISIBLE (700 3450);
FORCEPROP 1 LAST HDL_TAP TRUE
J 2
(375 3375);
DISPLAY 1.234043 (375 3375);
PAINT GREEN (375 3375);
DISPLAY INVISIBLE (375 3375);
FORCEPROP 1 LAST PATH I41
J 2
(700 3500);
DISPLAY 0.936170 (700 3500);
PAINT GREEN (700 3500);
DISPLAY INVISIBLE (700 3500);
FORCEADD SCONN288_H44441004..3
(1800 2650);
FORCEPROP 1 LAST LOCATION J4G3
J 0
(1350 4050);
DISPLAY 0.617021 (1350 4050);
PAINT AQUA (1350 4050);
FORCEPROP 1 LAST PART_NUMBER H44441-004
J 0
(1350 1300);
DISPLAY 0.617021 (1350 1300);
PAINT BLUE (1350 1300);
FORCEPROP 1 LAST MATERIAL SCONN
J 0
(1350 4000);
DISPLAY 0.617021 (1350 4000);
PAINT SKYBLUE (1350 4000);
FORCEPROP 2 LASTPIN (1300 3800) $PN 2
J 2
(1290 3810);
DISPLAY 0.617021 (1290 3810);
PAINT ORANGE (1290 3810);
FORCEPROP 2 LASTPIN (1300 3750) $PN 4
J 2
(1290 3760);
DISPLAY 0.617021 (1290 3760);
PAINT ORANGE (1290 3760);
FORCEPROP 2 LASTPIN (1300 3700) $PN 6
J 2
(1290 3710);
DISPLAY 0.617021 (1290 3710);
PAINT ORANGE (1290 3710);
FORCEPROP 2 LASTPIN (1300 3650) $PN 9
J 2
(1290 3660);
DISPLAY 0.617021 (1290 3660);
PAINT ORANGE (1290 3660);
FORCEPROP 2 LASTPIN (1300 3600) $PN 11
J 2
(1290 3610);
DISPLAY 0.617021 (1290 3610);
PAINT ORANGE (1290 3610);
FORCEPROP 2 LASTPIN (1300 3550) $PN 13
J 2
(1290 3560);
DISPLAY 0.617021 (1290 3560);
PAINT ORANGE (1290 3560);
FORCEPROP 2 LASTPIN (1300 3500) $PN 15
J 2
(1290 3510);
DISPLAY 0.617021 (1290 3510);
PAINT ORANGE (1290 3510);
FORCEPROP 2 LASTPIN (1300 3450) $PN 17
J 2
(1290 3460);
DISPLAY 0.617021 (1290 3460);
PAINT ORANGE (1290 3460);
FORCEPROP 2 LASTPIN (1300 3400) $PN 20
J 2
(1290 3410);
DISPLAY 0.617021 (1290 3410);
PAINT ORANGE (1290 3410);
FORCEPROP 2 LASTPIN (1300 3350) $PN 22
J 2
(1290 3360);
DISPLAY 0.617021 (1290 3360);
PAINT ORANGE (1290 3360);
FORCEPROP 2 LASTPIN (1300 3300) $PN 24
J 2
(1290 3310);
DISPLAY 0.617021 (1290 3310);
PAINT ORANGE (1290 3310);
FORCEPROP 2 LASTPIN (1300 3250) $PN 26
J 2
(1290 3260);
DISPLAY 0.617021 (1290 3260);
PAINT ORANGE (1290 3260);
FORCEPROP 2 LASTPIN (1300 3150) $PN 31
J 2
(1290 3160);
DISPLAY 0.617021 (1290 3160);
PAINT ORANGE (1290 3160);
FORCEPROP 2 LASTPIN (1300 3100) $PN 33
J 2
(1290 3110);
DISPLAY 0.617021 (1290 3110);
PAINT ORANGE (1290 3110);
FORCEPROP 2 LASTPIN (1300 3050) $PN 35
J 2
(1290 3060);
DISPLAY 0.617021 (1290 3060);
PAINT ORANGE (1290 3060);
FORCEPROP 2 LASTPIN (1300 3000) $PN 37
J 2
(1290 3010);
DISPLAY 0.617021 (1290 3010);
PAINT ORANGE (1290 3010);
FORCEPROP 2 LASTPIN (1300 2950) $PN 39
J 2
(1290 2960);
DISPLAY 0.617021 (1290 2960);
PAINT ORANGE (1290 2960);
FORCEPROP 2 LASTPIN (1300 2900) $PN 42
J 2
(1290 2910);
DISPLAY 0.617021 (1290 2910);
PAINT ORANGE (1290 2910);
FORCEPROP 2 LASTPIN (1300 2850) $PN 44
J 2
(1290 2860);
DISPLAY 0.617021 (1290 2860);
PAINT ORANGE (1290 2860);
FORCEPROP 2 LASTPIN (1300 2800) $PN 46
J 2
(1290 2810);
DISPLAY 0.617021 (1290 2810);
PAINT ORANGE (1290 2810);
FORCEPROP 2 LASTPIN (1300 2750) $PN 48
J 2
(1290 2760);
DISPLAY 0.617021 (1290 2760);
PAINT ORANGE (1290 2760);
FORCEPROP 2 LASTPIN (1300 2700) $PN 50
J 2
(1290 2710);
DISPLAY 0.617021 (1290 2710);
PAINT ORANGE (1290 2710);
FORCEPROP 2 LASTPIN (1300 2650) $PN 53
J 2
(1290 2660);
DISPLAY 0.617021 (1290 2660);
PAINT ORANGE (1290 2660);
FORCEPROP 2 LASTPIN (1300 2600) $PN 55
J 2
(1290 2610);
DISPLAY 0.617021 (1290 2610);
PAINT ORANGE (1290 2610);
FORCEPROP 2 LASTPIN (1300 2550) $PN 57
J 2
(1290 2560);
DISPLAY 0.617021 (1290 2560);
PAINT ORANGE (1290 2560);
FORCEPROP 2 LASTPIN (1300 2500) $PN 94
J 2
(1290 2510);
DISPLAY 0.617021 (1290 2510);
PAINT ORANGE (1290 2510);
FORCEPROP 2 LASTPIN (1300 2450) $PN 96
J 2
(1290 2460);
DISPLAY 0.617021 (1290 2460);
PAINT ORANGE (1290 2460);
FORCEPROP 2 LASTPIN (1300 2400) $PN 98
J 2
(1290 2410);
DISPLAY 0.617021 (1290 2410);
PAINT ORANGE (1290 2410);
FORCEPROP 2 LASTPIN (1300 2350) $PN 101
J 2
(1290 2360);
DISPLAY 0.617021 (1290 2360);
PAINT ORANGE (1290 2360);
FORCEPROP 2 LASTPIN (1300 2300) $PN 103
J 2
(1290 2310);
DISPLAY 0.617021 (1290 2310);
PAINT ORANGE (1290 2310);
FORCEPROP 2 LASTPIN (1300 2250) $PN 105
J 2
(1290 2260);
DISPLAY 0.617021 (1290 2260);
PAINT ORANGE (1290 2260);
FORCEPROP 2 LASTPIN (1300 2200) $PN 107
J 2
(1290 2210);
DISPLAY 0.617021 (1290 2210);
PAINT ORANGE (1290 2210);
FORCEPROP 2 LASTPIN (1300 2150) $PN 109
J 2
(1290 2160);
DISPLAY 0.617021 (1290 2160);
PAINT ORANGE (1290 2160);
FORCEPROP 2 LASTPIN (1300 2100) $PN 112
J 2
(1290 2110);
DISPLAY 0.617021 (1290 2110);
PAINT ORANGE (1290 2110);
FORCEPROP 2 LASTPIN (1300 2050) $PN 114
J 2
(1290 2060);
DISPLAY 0.617021 (1290 2060);
PAINT ORANGE (1290 2060);
FORCEPROP 2 LASTPIN (1300 2000) $PN 116
J 2
(1290 2010);
DISPLAY 0.617021 (1290 2010);
PAINT ORANGE (1290 2010);
FORCEPROP 2 LASTPIN (1300 1900) $PN 120
J 2
(1290 1910);
DISPLAY 0.617021 (1290 1910);
PAINT ORANGE (1290 1910);
FORCEPROP 2 LASTPIN (1300 1850) $PN 123
J 2
(1290 1860);
DISPLAY 0.617021 (1290 1860);
PAINT ORANGE (1290 1860);
FORCEPROP 2 LASTPIN (1300 1800) $PN 125
J 2
(1290 1810);
DISPLAY 0.617021 (1290 1810);
PAINT ORANGE (1290 1810);
FORCEPROP 2 LASTPIN (1300 1750) $PN 127
J 2
(1290 1760);
DISPLAY 0.617021 (1290 1760);
PAINT ORANGE (1290 1760);
FORCEPROP 2 LASTPIN (1300 1700) $PN 129
J 2
(1290 1710);
DISPLAY 0.617021 (1290 1710);
PAINT ORANGE (1290 1710);
FORCEPROP 2 LASTPIN (1300 1650) $PN 131
J 2
(1290 1660);
DISPLAY 0.617021 (1290 1660);
PAINT ORANGE (1290 1660);
FORCEPROP 2 LASTPIN (1300 1600) $PN 134
J 2
(1290 1610);
DISPLAY 0.617021 (1290 1610);
PAINT ORANGE (1290 1610);
FORCEPROP 2 LASTPIN (1300 1550) $PN 136
J 2
(1290 1560);
DISPLAY 0.617021 (1290 1560);
PAINT ORANGE (1290 1560);
FORCEPROP 2 LASTPIN (2300 3800) $PN 147
J 0
(2310 3810);
DISPLAY 0.617021 (2310 3810);
PAINT ORANGE (2310 3810);
FORCEPROP 2 LASTPIN (2300 3750) $PN 149
J 0
(2310 3760);
DISPLAY 0.617021 (2310 3760);
PAINT ORANGE (2310 3760);
FORCEPROP 2 LASTPIN (2300 3700) $PN 151
J 0
(2310 3710);
DISPLAY 0.617021 (2310 3710);
PAINT ORANGE (2310 3710);
FORCEPROP 2 LASTPIN (2300 3650) $PN 154
J 0
(2310 3660);
DISPLAY 0.617021 (2310 3660);
PAINT ORANGE (2310 3660);
FORCEPROP 2 LASTPIN (2300 3600) $PN 156
J 0
(2310 3610);
DISPLAY 0.617021 (2310 3610);
PAINT ORANGE (2310 3610);
FORCEPROP 2 LASTPIN (2300 3550) $PN 158
J 0
(2310 3560);
DISPLAY 0.617021 (2310 3560);
PAINT ORANGE (2310 3560);
FORCEPROP 2 LASTPIN (2300 3500) $PN 160
J 0
(2310 3510);
DISPLAY 0.617021 (2310 3510);
PAINT ORANGE (2310 3510);
FORCEPROP 2 LASTPIN (2300 3450) $PN 162
J 0
(2310 3460);
DISPLAY 0.617021 (2310 3460);
PAINT ORANGE (2310 3460);
FORCEPROP 2 LASTPIN (2300 3400) $PN 165
J 0
(2310 3410);
DISPLAY 0.617021 (2310 3410);
PAINT ORANGE (2310 3410);
FORCEPROP 2 LASTPIN (2300 3350) $PN 167
J 0
(2310 3360);
DISPLAY 0.617021 (2310 3360);
PAINT ORANGE (2310 3360);
FORCEPROP 2 LASTPIN (2300 3300) $PN 169
J 0
(2310 3310);
DISPLAY 0.617021 (2310 3310);
PAINT ORANGE (2310 3310);
FORCEPROP 2 LASTPIN (2300 3250) $PN 171
J 0
(2310 3260);
DISPLAY 0.617021 (2310 3260);
PAINT ORANGE (2310 3260);
FORCEPROP 2 LASTPIN (2300 3200) $PN 173
J 0
(2310 3210);
DISPLAY 0.617021 (2310 3210);
PAINT ORANGE (2310 3210);
FORCEPROP 2 LASTPIN (2300 3150) $PN 176
J 0
(2310 3160);
DISPLAY 0.617021 (2310 3160);
PAINT ORANGE (2310 3160);
FORCEPROP 2 LASTPIN (2300 3100) $PN 178
J 0
(2310 3110);
DISPLAY 0.617021 (2310 3110);
PAINT ORANGE (2310 3110);
FORCEPROP 2 LASTPIN (2300 3050) $PN 180
J 0
(2310 3060);
DISPLAY 0.617021 (2310 3060);
PAINT ORANGE (2310 3060);
FORCEPROP 2 LASTPIN (2300 2950) $PN 184
J 0
(2310 2960);
DISPLAY 0.617021 (2310 2960);
PAINT ORANGE (2310 2960);
FORCEPROP 2 LASTPIN (2300 2900) $PN 187
J 0
(2310 2910);
DISPLAY 0.617021 (2310 2910);
PAINT ORANGE (2310 2910);
FORCEPROP 2 LASTPIN (2300 2850) $PN 189
J 0
(2310 2860);
DISPLAY 0.617021 (2310 2860);
PAINT ORANGE (2310 2860);
FORCEPROP 2 LASTPIN (2300 2800) $PN 191
J 0
(2310 2810);
DISPLAY 0.617021 (2310 2810);
PAINT ORANGE (2310 2810);
FORCEPROP 2 LASTPIN (2300 2750) $PN 193
J 0
(2310 2760);
DISPLAY 0.617021 (2310 2760);
PAINT ORANGE (2310 2760);
FORCEPROP 2 LASTPIN (2300 2700) $PN 195
J 0
(2310 2710);
DISPLAY 0.617021 (2310 2710);
PAINT ORANGE (2310 2710);
FORCEPROP 2 LASTPIN (2300 2650) $PN 198
J 0
(2310 2660);
DISPLAY 0.617021 (2310 2660);
PAINT ORANGE (2310 2660);
FORCEPROP 2 LASTPIN (2300 2600) $PN 200
J 0
(2310 2610);
DISPLAY 0.617021 (2310 2610);
PAINT ORANGE (2310 2610);
FORCEPROP 2 LASTPIN (2300 2550) $PN 202
J 0
(2310 2560);
DISPLAY 0.617021 (2310 2560);
PAINT ORANGE (2310 2560);
FORCEPROP 2 LASTPIN (2300 2500) $PN 239
J 0
(2310 2510);
DISPLAY 0.617021 (2310 2510);
PAINT ORANGE (2310 2510);
FORCEPROP 2 LASTPIN (2300 2450) $PN 241
J 0
(2310 2460);
DISPLAY 0.617021 (2310 2460);
PAINT ORANGE (2310 2460);
FORCEPROP 2 LASTPIN (2300 2400) $PN 243
J 0
(2310 2410);
DISPLAY 0.617021 (2310 2410);
PAINT ORANGE (2310 2410);
FORCEPROP 2 LASTPIN (2300 2350) $PN 246
J 0
(2310 2360);
DISPLAY 0.617021 (2310 2360);
PAINT ORANGE (2310 2360);
FORCEPROP 2 LASTPIN (2300 2300) $PN 248
J 0
(2310 2310);
DISPLAY 0.617021 (2310 2310);
PAINT ORANGE (2310 2310);
FORCEPROP 2 LASTPIN (2300 2250) $PN 250
J 0
(2310 2260);
DISPLAY 0.617021 (2310 2260);
PAINT ORANGE (2310 2260);
FORCEPROP 2 LASTPIN (2300 2200) $PN 252
J 0
(2310 2210);
DISPLAY 0.617021 (2310 2210);
PAINT ORANGE (2310 2210);
FORCEPROP 2 LASTPIN (2300 2150) $PN 254
J 0
(2310 2160);
DISPLAY 0.617021 (2310 2160);
PAINT ORANGE (2310 2160);
FORCEPROP 2 LASTPIN (2300 2100) $PN 257
J 0
(2310 2110);
DISPLAY 0.617021 (2310 2110);
PAINT ORANGE (2310 2110);
FORCEPROP 2 LASTPIN (2300 2050) $PN 259
J 0
(2310 2060);
DISPLAY 0.617021 (2310 2060);
PAINT ORANGE (2310 2060);
FORCEPROP 2 LASTPIN (2300 2000) $PN 261
J 0
(2310 2010);
DISPLAY 0.617021 (2310 2010);
PAINT ORANGE (2310 2010);
FORCEPROP 2 LASTPIN (2300 1950) $PN 263
J 0
(2310 1960);
DISPLAY 0.617021 (2310 1960);
PAINT ORANGE (2310 1960);
FORCEPROP 2 LASTPIN (2300 1900) $PN 265
J 0
(2310 1910);
DISPLAY 0.617021 (2310 1910);
PAINT ORANGE (2310 1910);
FORCEPROP 2 LASTPIN (2300 1850) $PN 268
J 0
(2310 1860);
DISPLAY 0.617021 (2310 1860);
PAINT ORANGE (2310 1860);
FORCEPROP 2 LASTPIN (2300 1800) $PN 270
J 0
(2310 1810);
DISPLAY 0.617021 (2310 1810);
PAINT ORANGE (2310 1810);
FORCEPROP 2 LASTPIN (2300 1750) $PN 272
J 0
(2310 1760);
DISPLAY 0.617021 (2310 1760);
PAINT ORANGE (2310 1760);
FORCEPROP 2 LASTPIN (2300 1700) $PN 274
J 0
(2310 1710);
DISPLAY 0.617021 (2310 1710);
PAINT ORANGE (2310 1710);
FORCEPROP 2 LASTPIN (2300 1650) $PN 276
J 0
(2310 1660);
DISPLAY 0.617021 (2310 1660);
PAINT ORANGE (2310 1660);
FORCEPROP 2 LASTPIN (2300 1600) $PN 279
J 0
(2310 1610);
DISPLAY 0.617021 (2310 1610);
PAINT ORANGE (2310 1610);
FORCEPROP 2 LASTPIN (2300 1550) $PN 281
J 0
(2310 1560);
DISPLAY 0.617021 (2310 1560);
PAINT ORANGE (2310 1560);
FORCEPROP 2 LASTPIN (2300 1500) $PN 283
J 0
(2310 1510);
DISPLAY 0.617021 (2310 1510);
PAINT ORANGE (2310 1510);
FORCEPROP 2 LASTPIN (2300 3000) $PN 182
J 0
(2310 3010);
DISPLAY 0.617021 (2310 3010);
PAINT ORANGE (2310 3010);
FORCEPROP 2 LASTPIN (1300 3200) $PN 28
J 2
(1290 3210);
DISPLAY 0.617021 (1290 3210);
PAINT ORANGE (1290 3210);
FORCEPROP 2 LASTPIN (1300 1950) $PN 118
J 2
(1290 1960);
DISPLAY 0.617021 (1290 1960);
PAINT ORANGE (1290 1960);
FORCEPROP 2 LASTPIN (1300 1500) $PN 138
J 2
(1290 1510);
DISPLAY 0.617021 (1290 1510);
PAINT ORANGE (1290 1510);
FORCEPROP 1 LAST PACK_TYPE PIP
J 0
(1350 4100);
PAINT SKYBLUE (1350 4100);
DISPLAY INVISIBLE (1350 4100);
FORCEPROP 2 LAST BOM_COST MEM
J 0
(1800 2650);
PAINT ORANGE (1800 2650);
DISPLAY INVISIBLE (1800 2650);
FORCEPROP 2 LAST CDS_LIB mstr_sconn
J 0
(1800 2650);
PAINT ORANGE (1800 2650);
DISPLAY INVISIBLE (1800 2650);
FORCEPROP 2 LAST SEC_TYPE PIP
J 0
(1350 4100);
DISPLAY 1.021277 (1350 4100);
PAINT ORANGE (1350 4100);
DISPLAY INVISIBLE (1350 4100);
FORCEPROP 2 LAST SEC 3
J 0
(1350 4100);
DISPLAY 0.680851 (1350 4100);
PAINT MONO (1350 4100);
DISPLAY INVISIBLE (1350 4100);
FORCEPROP 2 LAST CDS_LOCATION J4G3
J 0
(1350 4050);
DISPLAY 0.617021 (1350 4050);
PAINT AQUA (1350 4050);
DISPLAY INVISIBLE (1350 4050);
FORCEPROP 1 LAST PATH I43
J 0
(1800 4000);
PAINT GREEN (1800 4000);
DISPLAY INVISIBLE (1800 4000);
FORCEPROP 2 LAST ROOM DDR4_CH_C
J 0
(1800 2650);
PAINT ORANGE (1800 2650);
DISPLAY INVISIBLE (1800 2650);
FORCEADD GND..1
R 2
(1100 1350);
FORCEPROP 3 LASTPIN (1100 1400) SIG_NAME GND\g
J 0
(1110 1410);
DISPLAY 0.659574 (1110 1410);
PAINT MONO (1110 1410);
DISPLAY INVISIBLE (1110 1410);
FORCEPROP 1 LAST VOLTAGE 0
J 0
(1100 1350);
PAINT SKYBLUE (1100 1350);
DISPLAY INVISIBLE (1100 1350);
FORCEPROP 2 LAST CDS_LIB mstr_symbols
J 0
(1100 1350);
DISPLAY 0.787234 (1100 1350);
PAINT MONO (1100 1350);
DISPLAY INVISIBLE (1100 1350);
FORCEPROP 1 LAST SIZE 1B
J 2
(1025 1300);
DISPLAY 1.170213 (1025 1300);
PAINT GREEN (1025 1300);
DISPLAY INVISIBLE (1025 1300);
FORCEPROP 2 LAST BOM_COST MEM
J 0
(1100 1355);
PAINT ORANGE (1100 1355);
DISPLAY INVISIBLE (1100 1355);
FORCEPROP 1 LAST BODY_TYPE PLUMBING
J 2
(1145 1307);
DISPLAY 0.340426 (1145 1307);
PAINT GREEN (1145 1307);
DISPLAY INVISIBLE (1145 1307);
FORCEPROP 1 LAST PATH I44
J 2
(1025 1350);
DISPLAY 0.936170 (1025 1350);
PAINT GREEN (1025 1350);
DISPLAY INVISIBLE (1025 1350);
FORCEPROP 2 LAST ROOM DDR4_CH_A
J 0
(1100 1355);
PAINT ORANGE (1100 1355);
DISPLAY INVISIBLE (1100 1355);
FORCEPROP 1 LAST HDL_POWER GND
J 2
(1100 1500);
DISPLAY 0.553191 (1100 1500);
PAINT GREEN (1100 1500);
DISPLAY INVISIBLE (1100 1500);
FORCEADD OFFPAGE..3
(-1150 4700);
FORCEPROP 2 LAST $XR1 48 
J 0
(-846 4700);
DISPLAY 0.638298 (-846 4700);
PAINT MONO (-846 4700);
FORCEPROP 2 LAST $XR0 25 
J 0
(-936 4700);
DISPLAY 0.638298 (-936 4700);
PAINT MONO (-936 4700);
FORCEPROP 2 LAST CDS_LIB mstr_standard
J 0
(-1150 4700);
DISPLAY 0.787234 (-1150 4700);
PAINT MONO (-1150 4700);
DISPLAY INVISIBLE (-1150 4700);
FORCEPROP 1 LAST OFFPAGE TRUE
J 0
(-825 4575);
DISPLAY 0.936170 (-825 4575);
PAINT GREEN (-825 4575);
DISPLAY INVISIBLE (-825 4575);
FORCEPROP 1 LAST COMMENT_BODY TRUE
J 0
(-1200 4600);
DISPLAY 0.936170 (-1200 4600);
PAINT GREEN (-1200 4600);
DISPLAY INVISIBLE (-1200 4600);
FORCEPROP 2 LAST PATH I45
J 0
(-950 4775);
DISPLAY 0.787234 (-950 4775);
PAINT MONO (-950 4775);
DISPLAY INVISIBLE (-950 4775);
FORCEADD TAP..6
R 2
(-1700 4650);
FORCEPROP 3 LASTPIN (-1750 4650) SIG_NAME M_C_DQ<62>
J 0
(-1740 4660);
DISPLAY 0.659574 (-1740 4660);
PAINT MONO (-1740 4660);
DISPLAY INVISIBLE (-1740 4660);
FORCEPROP 1 LASTPIN (-1750 4650) BN 62
J 2
(-1700 4660);
DISPLAY 0.617021 (-1700 4660);
PAINT PINK (-1700 4660);
FORCEPROP 2 LAST CDS_LIB mstr_standard
J 2
(-1700 4650);
DISPLAY 0.787234 (-1700 4650);
PAINT MONO (-1700 4650);
DISPLAY INVISIBLE (-1700 4650);
FORCEPROP 1 LAST BODY_TYPE PLUMBING
J 2
(-1700 4600);
DISPLAY 1.234043 (-1700 4600);
PAINT GREEN (-1700 4600);
DISPLAY INVISIBLE (-1700 4600);
FORCEPROP 1 LAST HDL_TAP TRUE
J 2
(-2025 4525);
DISPLAY 1.234043 (-2025 4525);
PAINT GREEN (-2025 4525);
DISPLAY INVISIBLE (-2025 4525);
FORCEPROP 1 LAST PATH I46
J 2
(-1700 4650);
DISPLAY 0.936170 (-1700 4650);
PAINT GREEN (-1700 4650);
DISPLAY INVISIBLE (-1700 4650);
FORCEADD TAP..6
R 2
(-1700 4600);
FORCEPROP 3 LASTPIN (-1750 4600) SIG_NAME M_C_DQ<63>
J 0
(-1740 4610);
DISPLAY 0.659574 (-1740 4610);
PAINT MONO (-1740 4610);
DISPLAY INVISIBLE (-1740 4610);
FORCEPROP 1 LASTPIN (-1750 4600) BN 63
J 2
(-1700 4610);
DISPLAY 0.617021 (-1700 4610);
PAINT PINK (-1700 4610);
FORCEPROP 2 LAST CDS_LIB mstr_standard
J 2
(-1700 4600);
DISPLAY 0.787234 (-1700 4600);
PAINT MONO (-1700 4600);
DISPLAY INVISIBLE (-1700 4600);
FORCEPROP 1 LAST BODY_TYPE PLUMBING
J 2
(-1700 4550);
DISPLAY 1.234043 (-1700 4550);
PAINT GREEN (-1700 4550);
DISPLAY INVISIBLE (-1700 4550);
FORCEPROP 1 LAST HDL_TAP TRUE
J 2
(-2025 4475);
DISPLAY 1.234043 (-2025 4475);
PAINT GREEN (-2025 4475);
DISPLAY INVISIBLE (-2025 4475);
FORCEPROP 1 LAST PATH I47
J 2
(-1700 4600);
DISPLAY 0.936170 (-1700 4600);
PAINT GREEN (-1700 4600);
DISPLAY INVISIBLE (-1700 4600);
FORCEADD TAP..6
R 2
(-1700 4450);
FORCEPROP 3 LASTPIN (-1750 4450) SIG_NAME M_C_DQ<58>
J 0
(-1740 4460);
DISPLAY 0.659574 (-1740 4460);
PAINT MONO (-1740 4460);
DISPLAY INVISIBLE (-1740 4460);
FORCEPROP 1 LASTPIN (-1750 4450) BN 58
J 2
(-1700 4460);
DISPLAY 0.617021 (-1700 4460);
PAINT PINK (-1700 4460);
FORCEPROP 2 LAST CDS_LIB mstr_standard
J 2
(-1700 4450);
DISPLAY 0.787234 (-1700 4450);
PAINT MONO (-1700 4450);
DISPLAY INVISIBLE (-1700 4450);
FORCEPROP 1 LAST BODY_TYPE PLUMBING
J 2
(-1700 4400);
DISPLAY 1.234043 (-1700 4400);
PAINT GREEN (-1700 4400);
DISPLAY INVISIBLE (-1700 4400);
FORCEPROP 1 LAST HDL_TAP TRUE
J 2
(-2025 4325);
DISPLAY 1.234043 (-2025 4325);
PAINT GREEN (-2025 4325);
DISPLAY INVISIBLE (-2025 4325);
FORCEPROP 1 LAST PATH I48
J 2
(-1700 4450);
DISPLAY 0.936170 (-1700 4450);
PAINT GREEN (-1700 4450);
DISPLAY INVISIBLE (-1700 4450);
FORCEADD TAP..6
R 2
(-1700 4500);
FORCEPROP 3 LASTPIN (-1750 4500) SIG_NAME M_C_DQ<61>
J 0
(-1740 4510);
DISPLAY 0.659574 (-1740 4510);
PAINT MONO (-1740 4510);
DISPLAY INVISIBLE (-1740 4510);
FORCEPROP 1 LASTPIN (-1750 4500) BN 61
J 2
(-1700 4510);
DISPLAY 0.617021 (-1700 4510);
PAINT PINK (-1700 4510);
FORCEPROP 2 LAST CDS_LIB mstr_standard
J 2
(-1700 4500);
DISPLAY 0.787234 (-1700 4500);
PAINT MONO (-1700 4500);
DISPLAY INVISIBLE (-1700 4500);
FORCEPROP 1 LAST BODY_TYPE PLUMBING
J 2
(-1700 4450);
DISPLAY 1.234043 (-1700 4450);
PAINT GREEN (-1700 4450);
DISPLAY INVISIBLE (-1700 4450);
FORCEPROP 1 LAST HDL_TAP TRUE
J 2
(-2025 4375);
DISPLAY 1.234043 (-2025 4375);
PAINT GREEN (-2025 4375);
DISPLAY INVISIBLE (-2025 4375);
FORCEPROP 1 LAST PATH I49
J 2
(-1700 4500);
DISPLAY 0.936170 (-1700 4500);
PAINT GREEN (-1700 4500);
DISPLAY INVISIBLE (-1700 4500);
FORCEADD TAP..6
R 2
(700 5100);
FORCEPROP 3 LASTPIN (650 5100) SIG_NAME M_C_DQS_DP<16>
J 0
(660 5110);
DISPLAY 0.659574 (660 5110);
PAINT MONO (660 5110);
DISPLAY INVISIBLE (660 5110);
FORCEPROP 1 LASTPIN (650 5100) BN 16
J 2
(700 5110);
DISPLAY 0.617021 (700 5110);
PAINT PINK (700 5110);
FORCEPROP 2 LAST CDS_LIB mstr_standard
J 0
(700 5100);
DISPLAY 0.787234 (700 5100);
PAINT MONO (700 5100);
DISPLAY INVISIBLE (700 5100);
FORCEPROP 1 LAST BODY_TYPE PLUMBING
J 2
(700 5050);
DISPLAY 1.234043 (700 5050);
PAINT GREEN (700 5050);
DISPLAY INVISIBLE (700 5050);
FORCEPROP 1 LAST HDL_TAP TRUE
J 2
(375 4975);
DISPLAY 1.234043 (375 4975);
PAINT GREEN (375 4975);
DISPLAY INVISIBLE (375 4975);
FORCEPROP 1 LAST PATH I5
J 2
(700 5100);
DISPLAY 0.936170 (700 5100);
PAINT GREEN (700 5100);
DISPLAY INVISIBLE (700 5100);
FORCEADD TAP..6
R 2
(-1700 4550);
FORCEPROP 3 LASTPIN (-1750 4550) SIG_NAME M_C_DQ<60>
J 0
(-1740 4560);
DISPLAY 0.659574 (-1740 4560);
PAINT MONO (-1740 4560);
DISPLAY INVISIBLE (-1740 4560);
FORCEPROP 1 LASTPIN (-1750 4550) BN 60
J 2
(-1700 4560);
DISPLAY 0.617021 (-1700 4560);
PAINT PINK (-1700 4560);
FORCEPROP 2 LAST CDS_LIB mstr_standard
J 2
(-1700 4550);
DISPLAY 0.787234 (-1700 4550);
PAINT MONO (-1700 4550);
DISPLAY INVISIBLE (-1700 4550);
FORCEPROP 1 LAST BODY_TYPE PLUMBING
J 2
(-1700 4500);
DISPLAY 1.234043 (-1700 4500);
PAINT GREEN (-1700 4500);
DISPLAY INVISIBLE (-1700 4500);
FORCEPROP 1 LAST HDL_TAP TRUE
J 2
(-2025 4425);
DISPLAY 1.234043 (-2025 4425);
PAINT GREEN (-2025 4425);
DISPLAY INVISIBLE (-2025 4425);
FORCEPROP 1 LAST PATH I50
J 2
(-1700 4550);
DISPLAY 0.936170 (-1700 4550);
PAINT GREEN (-1700 4550);
DISPLAY INVISIBLE (-1700 4550);
FORCEADD TAP..6
R 2
(-1700 4350);
FORCEPROP 3 LASTPIN (-1750 4350) SIG_NAME M_C_DQ<56>
J 0
(-1740 4360);
DISPLAY 0.659574 (-1740 4360);
PAINT MONO (-1740 4360);
DISPLAY INVISIBLE (-1740 4360);
FORCEPROP 1 LASTPIN (-1750 4350) BN 56
J 2
(-1700 4360);
DISPLAY 0.617021 (-1700 4360);
PAINT PINK (-1700 4360);
FORCEPROP 2 LAST CDS_LIB mstr_standard
J 2
(-1700 4350);
DISPLAY 0.787234 (-1700 4350);
PAINT MONO (-1700 4350);
DISPLAY INVISIBLE (-1700 4350);
FORCEPROP 1 LAST BODY_TYPE PLUMBING
J 2
(-1700 4300);
DISPLAY 1.234043 (-1700 4300);
PAINT GREEN (-1700 4300);
DISPLAY INVISIBLE (-1700 4300);
FORCEPROP 1 LAST HDL_TAP TRUE
J 2
(-2025 4225);
DISPLAY 1.234043 (-2025 4225);
PAINT GREEN (-2025 4225);
DISPLAY INVISIBLE (-2025 4225);
FORCEPROP 1 LAST PATH I51
J 2
(-1700 4350);
DISPLAY 0.936170 (-1700 4350);
PAINT GREEN (-1700 4350);
DISPLAY INVISIBLE (-1700 4350);
FORCEADD TAP..6
R 2
(-1700 4400);
FORCEPROP 3 LASTPIN (-1750 4400) SIG_NAME M_C_DQ<59>
J 0
(-1740 4410);
DISPLAY 0.659574 (-1740 4410);
PAINT MONO (-1740 4410);
DISPLAY INVISIBLE (-1740 4410);
FORCEPROP 1 LASTPIN (-1750 4400) BN 59
J 2
(-1700 4410);
DISPLAY 0.617021 (-1700 4410);
PAINT PINK (-1700 4410);
FORCEPROP 2 LAST CDS_LIB mstr_standard
J 2
(-1700 4400);
DISPLAY 0.787234 (-1700 4400);
PAINT MONO (-1700 4400);
DISPLAY INVISIBLE (-1700 4400);
FORCEPROP 1 LAST BODY_TYPE PLUMBING
J 2
(-1700 4350);
DISPLAY 1.234043 (-1700 4350);
PAINT GREEN (-1700 4350);
DISPLAY INVISIBLE (-1700 4350);
FORCEPROP 1 LAST HDL_TAP TRUE
J 2
(-2025 4275);
DISPLAY 1.234043 (-2025 4275);
PAINT GREEN (-2025 4275);
DISPLAY INVISIBLE (-2025 4275);
FORCEPROP 1 LAST PATH I52
J 2
(-1700 4400);
DISPLAY 0.936170 (-1700 4400);
PAINT GREEN (-1700 4400);
DISPLAY INVISIBLE (-1700 4400);
FORCEADD TAP..6
R 2
(-1700 4200);
FORCEPROP 3 LASTPIN (-1750 4200) SIG_NAME M_C_DQ<55>
J 0
(-1740 4210);
DISPLAY 0.659574 (-1740 4210);
PAINT MONO (-1740 4210);
DISPLAY INVISIBLE (-1740 4210);
FORCEPROP 1 LASTPIN (-1750 4200) BN 55
J 2
(-1700 4210);
DISPLAY 0.617021 (-1700 4210);
PAINT PINK (-1700 4210);
FORCEPROP 2 LAST CDS_LIB mstr_standard
J 2
(-1700 4200);
DISPLAY 0.787234 (-1700 4200);
PAINT MONO (-1700 4200);
DISPLAY INVISIBLE (-1700 4200);
FORCEPROP 1 LAST BODY_TYPE PLUMBING
J 2
(-1700 4150);
DISPLAY 1.234043 (-1700 4150);
PAINT GREEN (-1700 4150);
DISPLAY INVISIBLE (-1700 4150);
FORCEPROP 1 LAST HDL_TAP TRUE
J 2
(-2025 4075);
DISPLAY 1.234043 (-2025 4075);
PAINT GREEN (-2025 4075);
DISPLAY INVISIBLE (-2025 4075);
FORCEPROP 1 LAST PATH I53
J 2
(-1700 4200);
DISPLAY 0.936170 (-1700 4200);
PAINT GREEN (-1700 4200);
DISPLAY INVISIBLE (-1700 4200);
FORCEADD TAP..6
R 2
(-1700 4250);
FORCEPROP 3 LASTPIN (-1750 4250) SIG_NAME M_C_DQ<54>
J 0
(-1740 4260);
DISPLAY 0.659574 (-1740 4260);
PAINT MONO (-1740 4260);
DISPLAY INVISIBLE (-1740 4260);
FORCEPROP 1 LASTPIN (-1750 4250) BN 54
J 2
(-1700 4260);
DISPLAY 0.617021 (-1700 4260);
PAINT PINK (-1700 4260);
FORCEPROP 2 LAST CDS_LIB mstr_standard
J 2
(-1700 4250);
DISPLAY 0.787234 (-1700 4250);
PAINT MONO (-1700 4250);
DISPLAY INVISIBLE (-1700 4250);
FORCEPROP 1 LAST BODY_TYPE PLUMBING
J 2
(-1700 4200);
DISPLAY 1.234043 (-1700 4200);
PAINT GREEN (-1700 4200);
DISPLAY INVISIBLE (-1700 4200);
FORCEPROP 1 LAST HDL_TAP TRUE
J 2
(-2025 4125);
DISPLAY 1.234043 (-2025 4125);
PAINT GREEN (-2025 4125);
DISPLAY INVISIBLE (-2025 4125);
FORCEPROP 1 LAST PATH I54
J 2
(-1700 4250);
DISPLAY 0.936170 (-1700 4250);
PAINT GREEN (-1700 4250);
DISPLAY INVISIBLE (-1700 4250);
FORCEADD TAP..6
R 2
(-1700 4300);
FORCEPROP 3 LASTPIN (-1750 4300) SIG_NAME M_C_DQ<57>
J 0
(-1740 4310);
DISPLAY 0.659574 (-1740 4310);
PAINT MONO (-1740 4310);
DISPLAY INVISIBLE (-1740 4310);
FORCEPROP 1 LASTPIN (-1750 4300) BN 57
J 2
(-1700 4310);
DISPLAY 0.617021 (-1700 4310);
PAINT PINK (-1700 4310);
FORCEPROP 2 LAST CDS_LIB mstr_standard
J 2
(-1700 4300);
DISPLAY 0.787234 (-1700 4300);
PAINT MONO (-1700 4300);
DISPLAY INVISIBLE (-1700 4300);
FORCEPROP 1 LAST BODY_TYPE PLUMBING
J 2
(-1700 4250);
DISPLAY 1.234043 (-1700 4250);
PAINT GREEN (-1700 4250);
DISPLAY INVISIBLE (-1700 4250);
FORCEPROP 1 LAST HDL_TAP TRUE
J 2
(-2025 4175);
DISPLAY 1.234043 (-2025 4175);
PAINT GREEN (-2025 4175);
DISPLAY INVISIBLE (-2025 4175);
FORCEPROP 1 LAST PATH I55
J 2
(-1700 4300);
DISPLAY 0.936170 (-1700 4300);
PAINT GREEN (-1700 4300);
DISPLAY INVISIBLE (-1700 4300);
FORCEADD TAP..6
R 2
(-1700 4100);
FORCEPROP 3 LASTPIN (-1750 4100) SIG_NAME M_C_DQ<53>
J 0
(-1740 4110);
DISPLAY 0.659574 (-1740 4110);
PAINT MONO (-1740 4110);
DISPLAY INVISIBLE (-1740 4110);
FORCEPROP 1 LASTPIN (-1750 4100) BN 53
J 2
(-1700 4110);
DISPLAY 0.617021 (-1700 4110);
PAINT PINK (-1700 4110);
FORCEPROP 2 LAST CDS_LIB mstr_standard
J 2
(-1700 4100);
DISPLAY 0.787234 (-1700 4100);
PAINT MONO (-1700 4100);
DISPLAY INVISIBLE (-1700 4100);
FORCEPROP 1 LAST BODY_TYPE PLUMBING
J 2
(-1700 4050);
DISPLAY 1.234043 (-1700 4050);
PAINT GREEN (-1700 4050);
DISPLAY INVISIBLE (-1700 4050);
FORCEPROP 1 LAST HDL_TAP TRUE
J 2
(-2025 3975);
DISPLAY 1.234043 (-2025 3975);
PAINT GREEN (-2025 3975);
DISPLAY INVISIBLE (-2025 3975);
FORCEPROP 1 LAST PATH I56
J 2
(-1700 4100);
DISPLAY 0.936170 (-1700 4100);
PAINT GREEN (-1700 4100);
DISPLAY INVISIBLE (-1700 4100);
FORCEADD TAP..6
R 2
(-1700 4150);
FORCEPROP 3 LASTPIN (-1750 4150) SIG_NAME M_C_DQ<52>
J 0
(-1740 4160);
DISPLAY 0.659574 (-1740 4160);
PAINT MONO (-1740 4160);
DISPLAY INVISIBLE (-1740 4160);
FORCEPROP 1 LASTPIN (-1750 4150) BN 52
J 2
(-1700 4160);
DISPLAY 0.617021 (-1700 4160);
PAINT PINK (-1700 4160);
FORCEPROP 2 LAST CDS_LIB mstr_standard
J 2
(-1700 4150);
DISPLAY 0.787234 (-1700 4150);
PAINT MONO (-1700 4150);
DISPLAY INVISIBLE (-1700 4150);
FORCEPROP 1 LAST BODY_TYPE PLUMBING
J 2
(-1700 4100);
DISPLAY 1.234043 (-1700 4100);
PAINT GREEN (-1700 4100);
DISPLAY INVISIBLE (-1700 4100);
FORCEPROP 1 LAST HDL_TAP TRUE
J 2
(-2025 4025);
DISPLAY 1.234043 (-2025 4025);
PAINT GREEN (-2025 4025);
DISPLAY INVISIBLE (-2025 4025);
FORCEPROP 1 LAST PATH I57
J 2
(-1700 4150);
DISPLAY 0.936170 (-1700 4150);
PAINT GREEN (-1700 4150);
DISPLAY INVISIBLE (-1700 4150);
FORCEADD TAP..6
R 2
(-1700 4050);
FORCEPROP 3 LASTPIN (-1750 4050) SIG_NAME M_C_DQ<50>
J 0
(-1740 4060);
DISPLAY 0.659574 (-1740 4060);
PAINT MONO (-1740 4060);
DISPLAY INVISIBLE (-1740 4060);
FORCEPROP 1 LASTPIN (-1750 4050) BN 50
J 2
(-1700 4060);
DISPLAY 0.617021 (-1700 4060);
PAINT PINK (-1700 4060);
FORCEPROP 2 LAST CDS_LIB mstr_standard
J 2
(-1700 4050);
DISPLAY 0.787234 (-1700 4050);
PAINT MONO (-1700 4050);
DISPLAY INVISIBLE (-1700 4050);
FORCEPROP 1 LAST BODY_TYPE PLUMBING
J 2
(-1700 4000);
DISPLAY 1.234043 (-1700 4000);
PAINT GREEN (-1700 4000);
DISPLAY INVISIBLE (-1700 4000);
FORCEPROP 1 LAST HDL_TAP TRUE
J 2
(-2025 3925);
DISPLAY 1.234043 (-2025 3925);
PAINT GREEN (-2025 3925);
DISPLAY INVISIBLE (-2025 3925);
FORCEPROP 1 LAST PATH I58
J 2
(-1700 4050);
DISPLAY 0.936170 (-1700 4050);
PAINT GREEN (-1700 4050);
DISPLAY INVISIBLE (-1700 4050);
FORCEADD TAP..6
R 2
(-1700 4000);
FORCEPROP 3 LASTPIN (-1750 4000) SIG_NAME M_C_DQ<51>
J 0
(-1740 4010);
DISPLAY 0.659574 (-1740 4010);
PAINT MONO (-1740 4010);
DISPLAY INVISIBLE (-1740 4010);
FORCEPROP 1 LASTPIN (-1750 4000) BN 51
J 2
(-1700 4010);
DISPLAY 0.617021 (-1700 4010);
PAINT PINK (-1700 4010);
FORCEPROP 2 LAST CDS_LIB mstr_standard
J 2
(-1700 4000);
DISPLAY 0.787234 (-1700 4000);
PAINT MONO (-1700 4000);
DISPLAY INVISIBLE (-1700 4000);
FORCEPROP 1 LAST BODY_TYPE PLUMBING
J 2
(-1700 3950);
DISPLAY 1.234043 (-1700 3950);
PAINT GREEN (-1700 3950);
DISPLAY INVISIBLE (-1700 3950);
FORCEPROP 1 LAST HDL_TAP TRUE
J 2
(-2025 3875);
DISPLAY 1.234043 (-2025 3875);
PAINT GREEN (-2025 3875);
DISPLAY INVISIBLE (-2025 3875);
FORCEPROP 1 LAST PATH I59
J 2
(-1700 4000);
DISPLAY 0.936170 (-1700 4000);
PAINT GREEN (-1700 4000);
DISPLAY INVISIBLE (-1700 4000);
FORCEADD TAP..6
R 2
(900 4950);
FORCEPROP 3 LASTPIN (850 4950) SIG_NAME M_C_DQS_DN<15>
J 0
(860 4960);
DISPLAY 0.659574 (860 4960);
PAINT MONO (860 4960);
DISPLAY INVISIBLE (860 4960);
FORCEPROP 1 LASTPIN (850 4950) BN 15
J 2
(900 4960);
DISPLAY 0.617021 (900 4960);
PAINT PINK (900 4960);
FORCEPROP 2 LAST CDS_LIB mstr_standard
J 0
(900 4950);
DISPLAY 0.787234 (900 4950);
PAINT MONO (900 4950);
DISPLAY INVISIBLE (900 4950);
FORCEPROP 1 LAST BODY_TYPE PLUMBING
J 2
(900 4900);
DISPLAY 1.234043 (900 4900);
PAINT GREEN (900 4900);
DISPLAY INVISIBLE (900 4900);
FORCEPROP 1 LAST HDL_TAP TRUE
J 2
(575 4825);
DISPLAY 1.234043 (575 4825);
PAINT GREEN (575 4825);
DISPLAY INVISIBLE (575 4825);
FORCEPROP 1 LAST PATH I6
J 2
(900 4950);
DISPLAY 0.936170 (900 4950);
PAINT GREEN (900 4950);
DISPLAY INVISIBLE (900 4950);
FORCEADD TAP..6
R 2
(-1700 3950);
FORCEPROP 3 LASTPIN (-1750 3950) SIG_NAME M_C_DQ<48>
J 0
(-1740 3960);
DISPLAY 0.659574 (-1740 3960);
PAINT MONO (-1740 3960);
DISPLAY INVISIBLE (-1740 3960);
FORCEPROP 1 LASTPIN (-1750 3950) BN 48
J 2
(-1700 3960);
DISPLAY 0.617021 (-1700 3960);
PAINT PINK (-1700 3960);
FORCEPROP 2 LAST CDS_LIB mstr_standard
J 2
(-1700 3950);
DISPLAY 0.787234 (-1700 3950);
PAINT MONO (-1700 3950);
DISPLAY INVISIBLE (-1700 3950);
FORCEPROP 1 LAST BODY_TYPE PLUMBING
J 2
(-1700 3900);
DISPLAY 1.234043 (-1700 3900);
PAINT GREEN (-1700 3900);
DISPLAY INVISIBLE (-1700 3900);
FORCEPROP 1 LAST HDL_TAP TRUE
J 2
(-2025 3825);
DISPLAY 1.234043 (-2025 3825);
PAINT GREEN (-2025 3825);
DISPLAY INVISIBLE (-2025 3825);
FORCEPROP 1 LAST PATH I60
J 2
(-1700 3950);
DISPLAY 0.936170 (-1700 3950);
PAINT GREEN (-1700 3950);
DISPLAY INVISIBLE (-1700 3950);
FORCEADD SCONN288_H44441004..2
(0 4350);
FORCEPROP 1 LAST LOCATION J4G3
J 0
(-400 5450);
DISPLAY 0.617021 (-400 5450);
PAINT AQUA (-400 5450);
FORCEPROP 1 LAST PART_NUMBER H44441-004
J 0
(-400 3250);
DISPLAY 0.617021 (-400 3250);
PAINT BLUE (-400 3250);
FORCEPROP 1 LAST MATERIAL SCONN
J 0
(-400 5400);
DISPLAY 0.617021 (-400 5400);
PAINT SKYBLUE (-400 5400);
FORCEPROP 2 LASTPIN (450 5200) $PN 51
J 0
(460 5210);
DISPLAY 0.617021 (460 5210);
PAINT ORANGE (460 5210);
FORCEPROP 2 LASTPIN (450 5150) $PN 52
J 0
(460 5160);
DISPLAY 0.617021 (460 5160);
PAINT ORANGE (460 5160);
FORCEPROP 2 LASTPIN (450 5100) $PN 132
J 0
(460 5110);
DISPLAY 0.617021 (460 5110);
PAINT ORANGE (460 5110);
FORCEPROP 2 LASTPIN (450 5050) $PN 133
J 0
(460 5060);
DISPLAY 0.617021 (460 5060);
PAINT ORANGE (460 5060);
FORCEPROP 2 LASTPIN (450 5000) $PN 121
J 0
(460 5010);
DISPLAY 0.617021 (460 5010);
PAINT ORANGE (460 5010);
FORCEPROP 2 LASTPIN (450 4950) $PN 122
J 0
(460 4960);
DISPLAY 0.617021 (460 4960);
PAINT ORANGE (460 4960);
FORCEPROP 2 LASTPIN (450 4900) $PN 110
J 0
(460 4910);
DISPLAY 0.617021 (460 4910);
PAINT ORANGE (460 4910);
FORCEPROP 2 LASTPIN (450 4850) $PN 111
J 0
(460 4860);
DISPLAY 0.617021 (460 4860);
PAINT ORANGE (460 4860);
FORCEPROP 2 LASTPIN (450 4800) $PN 99
J 0
(460 4810);
DISPLAY 0.617021 (460 4810);
PAINT ORANGE (460 4810);
FORCEPROP 2 LASTPIN (450 4750) $PN 100
J 0
(460 4760);
DISPLAY 0.617021 (460 4760);
PAINT ORANGE (460 4760);
FORCEPROP 2 LASTPIN (450 4650) $PN 41
J 0
(460 4660);
DISPLAY 0.617021 (460 4660);
PAINT ORANGE (460 4660);
FORCEPROP 2 LASTPIN (450 4600) $PN 29
J 0
(460 4610);
DISPLAY 0.617021 (460 4610);
PAINT ORANGE (460 4610);
FORCEPROP 2 LASTPIN (450 4550) $PN 30
J 0
(460 4560);
DISPLAY 0.617021 (460 4560);
PAINT ORANGE (460 4560);
FORCEPROP 2 LASTPIN (450 4500) $PN 18
J 0
(460 4510);
DISPLAY 0.617021 (460 4510);
PAINT ORANGE (460 4510);
FORCEPROP 2 LASTPIN (450 4450) $PN 19
J 0
(460 4460);
DISPLAY 0.617021 (460 4460);
PAINT ORANGE (460 4460);
FORCEPROP 2 LASTPIN (450 4400) $PN 7
J 0
(460 4410);
DISPLAY 0.617021 (460 4410);
PAINT ORANGE (460 4410);
FORCEPROP 2 LASTPIN (450 4350) $PN 8
J 0
(460 4360);
DISPLAY 0.617021 (460 4360);
PAINT ORANGE (460 4360);
FORCEPROP 2 LASTPIN (450 4300) $PN 197
J 0
(460 4310);
DISPLAY 0.617021 (460 4310);
PAINT ORANGE (460 4310);
FORCEPROP 2 LASTPIN (450 4250) $PN 196
J 0
(460 4260);
DISPLAY 0.617021 (460 4260);
PAINT ORANGE (460 4260);
FORCEPROP 2 LASTPIN (450 4200) $PN 278
J 0
(460 4210);
DISPLAY 0.617021 (460 4210);
PAINT ORANGE (460 4210);
FORCEPROP 2 LASTPIN (450 4150) $PN 277
J 0
(460 4160);
DISPLAY 0.617021 (460 4160);
PAINT ORANGE (460 4160);
FORCEPROP 2 LASTPIN (450 4100) $PN 267
J 0
(460 4110);
DISPLAY 0.617021 (460 4110);
PAINT ORANGE (460 4110);
FORCEPROP 2 LASTPIN (450 4050) $PN 266
J 0
(460 4060);
DISPLAY 0.617021 (460 4060);
PAINT ORANGE (460 4060);
FORCEPROP 2 LASTPIN (450 4000) $PN 256
J 0
(460 4010);
DISPLAY 0.617021 (460 4010);
PAINT ORANGE (460 4010);
FORCEPROP 2 LASTPIN (450 3950) $PN 255
J 0
(460 3960);
DISPLAY 0.617021 (460 3960);
PAINT ORANGE (460 3960);
FORCEPROP 2 LASTPIN (450 3900) $PN 245
J 0
(460 3910);
DISPLAY 0.617021 (460 3910);
PAINT ORANGE (460 3910);
FORCEPROP 2 LASTPIN (450 3850) $PN 244
J 0
(460 3860);
DISPLAY 0.617021 (460 3860);
PAINT ORANGE (460 3860);
FORCEPROP 2 LASTPIN (450 3800) $PN 186
J 0
(460 3810);
DISPLAY 0.617021 (460 3810);
PAINT ORANGE (460 3810);
FORCEPROP 2 LASTPIN (450 3750) $PN 185
J 0
(460 3760);
DISPLAY 0.617021 (460 3760);
PAINT ORANGE (460 3760);
FORCEPROP 2 LASTPIN (450 3700) $PN 175
J 0
(460 3710);
DISPLAY 0.617021 (460 3710);
PAINT ORANGE (460 3710);
FORCEPROP 2 LASTPIN (450 3650) $PN 174
J 0
(460 3660);
DISPLAY 0.617021 (460 3660);
PAINT ORANGE (460 3660);
FORCEPROP 2 LASTPIN (450 3600) $PN 164
J 0
(460 3610);
DISPLAY 0.617021 (460 3610);
PAINT ORANGE (460 3610);
FORCEPROP 2 LASTPIN (450 3550) $PN 163
J 0
(460 3560);
DISPLAY 0.617021 (460 3560);
PAINT ORANGE (460 3560);
FORCEPROP 2 LASTPIN (450 3450) $PN 152
J 0
(460 3460);
DISPLAY 0.617021 (460 3460);
PAINT ORANGE (460 3460);
FORCEPROP 2 LASTPIN (450 4700) $PN 40
J 0
(460 4710);
DISPLAY 0.617021 (460 4710);
PAINT ORANGE (460 4710);
FORCEPROP 2 LASTPIN (450 3500) $PN 153
J 0
(460 3510);
DISPLAY 0.617021 (460 3510);
PAINT ORANGE (460 3510);
FORCEPROP 1 LAST PACK_TYPE PIP
J 0
(-400 5500);
PAINT SKYBLUE (-400 5500);
DISPLAY INVISIBLE (-400 5500);
FORCEPROP 2 LAST BOM_COST MEM
J 0
(0 4350);
PAINT ORANGE (0 4350);
DISPLAY INVISIBLE (0 4350);
FORCEPROP 2 LAST CDS_LIB mstr_sconn
J 0
(0 4350);
PAINT ORANGE (0 4350);
DISPLAY INVISIBLE (0 4350);
FORCEPROP 2 LAST SEC_TYPE PIP
J 0
(-400 5500);
DISPLAY 1.021277 (-400 5500);
PAINT ORANGE (-400 5500);
DISPLAY INVISIBLE (-400 5500);
FORCEPROP 2 LAST SEC 2
J 0
(-400 5500);
DISPLAY 0.680851 (-400 5500);
PAINT MONO (-400 5500);
DISPLAY INVISIBLE (-400 5500);
FORCEPROP 2 LAST CDS_LOCATION J4G3
J 0
(-400 5450);
DISPLAY 0.617021 (-400 5450);
PAINT AQUA (-400 5450);
DISPLAY INVISIBLE (-400 5450);
FORCEPROP 1 LAST PATH I61
J 0
(0 5400);
PAINT GREEN (0 5400);
DISPLAY INVISIBLE (0 5400);
FORCEPROP 2 LAST ROOM DDR4_CH_C
J 0
(-400 5550);
PAINT ORANGE (-400 5550);
DISPLAY INVISIBLE (-400 5550);
FORCEADD TAP..6
R 2
(-1700 3800);
FORCEPROP 3 LASTPIN (-1750 3800) SIG_NAME M_C_DQ<47>
J 0
(-1740 3810);
DISPLAY 0.659574 (-1740 3810);
PAINT MONO (-1740 3810);
DISPLAY INVISIBLE (-1740 3810);
FORCEPROP 1 LASTPIN (-1750 3800) BN 47
J 2
(-1700 3810);
DISPLAY 0.617021 (-1700 3810);
PAINT PINK (-1700 3810);
FORCEPROP 2 LAST CDS_LIB mstr_standard
J 2
(-1700 3800);
DISPLAY 0.787234 (-1700 3800);
PAINT MONO (-1700 3800);
DISPLAY INVISIBLE (-1700 3800);
FORCEPROP 1 LAST BODY_TYPE PLUMBING
J 2
(-1700 3750);
DISPLAY 1.234043 (-1700 3750);
PAINT GREEN (-1700 3750);
DISPLAY INVISIBLE (-1700 3750);
FORCEPROP 1 LAST HDL_TAP TRUE
J 2
(-2025 3675);
DISPLAY 1.234043 (-2025 3675);
PAINT GREEN (-2025 3675);
DISPLAY INVISIBLE (-2025 3675);
FORCEPROP 1 LAST PATH I62
J 2
(-1700 3800);
DISPLAY 0.936170 (-1700 3800);
PAINT GREEN (-1700 3800);
DISPLAY INVISIBLE (-1700 3800);
FORCEADD TAP..6
R 2
(-1700 3850);
FORCEPROP 3 LASTPIN (-1750 3850) SIG_NAME M_C_DQ<46>
J 0
(-1740 3860);
DISPLAY 0.659574 (-1740 3860);
PAINT MONO (-1740 3860);
DISPLAY INVISIBLE (-1740 3860);
FORCEPROP 1 LASTPIN (-1750 3850) BN 46
J 2
(-1700 3860);
DISPLAY 0.617021 (-1700 3860);
PAINT PINK (-1700 3860);
FORCEPROP 2 LAST CDS_LIB mstr_standard
J 2
(-1700 3850);
DISPLAY 0.787234 (-1700 3850);
PAINT MONO (-1700 3850);
DISPLAY INVISIBLE (-1700 3850);
FORCEPROP 1 LAST BODY_TYPE PLUMBING
J 2
(-1700 3800);
DISPLAY 1.234043 (-1700 3800);
PAINT GREEN (-1700 3800);
DISPLAY INVISIBLE (-1700 3800);
FORCEPROP 1 LAST HDL_TAP TRUE
J 2
(-2025 3725);
DISPLAY 1.234043 (-2025 3725);
PAINT GREEN (-2025 3725);
DISPLAY INVISIBLE (-2025 3725);
FORCEPROP 1 LAST PATH I63
J 2
(-1700 3850);
DISPLAY 0.936170 (-1700 3850);
PAINT GREEN (-1700 3850);
DISPLAY INVISIBLE (-1700 3850);
FORCEADD TAP..6
R 2
(-1700 3900);
FORCEPROP 3 LASTPIN (-1750 3900) SIG_NAME M_C_DQ<49>
J 0
(-1740 3910);
DISPLAY 0.659574 (-1740 3910);
PAINT MONO (-1740 3910);
DISPLAY INVISIBLE (-1740 3910);
FORCEPROP 1 LASTPIN (-1750 3900) BN 49
J 2
(-1700 3910);
DISPLAY 0.617021 (-1700 3910);
PAINT PINK (-1700 3910);
FORCEPROP 2 LAST CDS_LIB mstr_standard
J 2
(-1700 3900);
DISPLAY 0.787234 (-1700 3900);
PAINT MONO (-1700 3900);
DISPLAY INVISIBLE (-1700 3900);
FORCEPROP 1 LAST BODY_TYPE PLUMBING
J 2
(-1700 3850);
DISPLAY 1.234043 (-1700 3850);
PAINT GREEN (-1700 3850);
DISPLAY INVISIBLE (-1700 3850);
FORCEPROP 1 LAST HDL_TAP TRUE
J 2
(-2025 3775);
DISPLAY 1.234043 (-2025 3775);
PAINT GREEN (-2025 3775);
DISPLAY INVISIBLE (-2025 3775);
FORCEPROP 1 LAST PATH I64
J 2
(-1700 3900);
DISPLAY 0.936170 (-1700 3900);
PAINT GREEN (-1700 3900);
DISPLAY INVISIBLE (-1700 3900);
FORCEADD TAP..6
R 2
(-1700 3750);
FORCEPROP 3 LASTPIN (-1750 3750) SIG_NAME M_C_DQ<44>
J 0
(-1740 3760);
DISPLAY 0.659574 (-1740 3760);
PAINT MONO (-1740 3760);
DISPLAY INVISIBLE (-1740 3760);
FORCEPROP 1 LASTPIN (-1750 3750) BN 44
J 2
(-1700 3760);
DISPLAY 0.617021 (-1700 3760);
PAINT PINK (-1700 3760);
FORCEPROP 2 LAST CDS_LIB mstr_standard
J 2
(-1700 3750);
DISPLAY 0.787234 (-1700 3750);
PAINT MONO (-1700 3750);
DISPLAY INVISIBLE (-1700 3750);
FORCEPROP 1 LAST BODY_TYPE PLUMBING
J 2
(-1700 3700);
DISPLAY 1.234043 (-1700 3700);
PAINT GREEN (-1700 3700);
DISPLAY INVISIBLE (-1700 3700);
FORCEPROP 1 LAST HDL_TAP TRUE
J 2
(-2025 3625);
DISPLAY 1.234043 (-2025 3625);
PAINT GREEN (-2025 3625);
DISPLAY INVISIBLE (-2025 3625);
FORCEPROP 1 LAST PATH I65
J 2
(-1700 3750);
DISPLAY 0.936170 (-1700 3750);
PAINT GREEN (-1700 3750);
DISPLAY INVISIBLE (-1700 3750);
FORCEADD TAP..6
R 2
(-1700 3700);
FORCEPROP 3 LASTPIN (-1750 3700) SIG_NAME M_C_DQ<45>
J 0
(-1740 3710);
DISPLAY 0.659574 (-1740 3710);
PAINT MONO (-1740 3710);
DISPLAY INVISIBLE (-1740 3710);
FORCEPROP 1 LASTPIN (-1750 3700) BN 45
J 2
(-1700 3710);
DISPLAY 0.617021 (-1700 3710);
PAINT PINK (-1700 3710);
FORCEPROP 2 LAST CDS_LIB mstr_standard
J 2
(-1700 3700);
DISPLAY 0.787234 (-1700 3700);
PAINT MONO (-1700 3700);
DISPLAY INVISIBLE (-1700 3700);
FORCEPROP 1 LAST BODY_TYPE PLUMBING
J 2
(-1700 3650);
DISPLAY 1.234043 (-1700 3650);
PAINT GREEN (-1700 3650);
DISPLAY INVISIBLE (-1700 3650);
FORCEPROP 1 LAST HDL_TAP TRUE
J 2
(-2025 3575);
DISPLAY 1.234043 (-2025 3575);
PAINT GREEN (-2025 3575);
DISPLAY INVISIBLE (-2025 3575);
FORCEPROP 1 LAST PATH I66
J 2
(-1700 3700);
DISPLAY 0.936170 (-1700 3700);
PAINT GREEN (-1700 3700);
DISPLAY INVISIBLE (-1700 3700);
FORCEADD TAP..6
R 2
(-1700 3650);
FORCEPROP 3 LASTPIN (-1750 3650) SIG_NAME M_C_DQ<42>
J 0
(-1740 3660);
DISPLAY 0.659574 (-1740 3660);
PAINT MONO (-1740 3660);
DISPLAY INVISIBLE (-1740 3660);
FORCEPROP 1 LASTPIN (-1750 3650) BN 42
J 2
(-1700 3660);
DISPLAY 0.617021 (-1700 3660);
PAINT PINK (-1700 3660);
FORCEPROP 2 LAST CDS_LIB mstr_standard
J 2
(-1700 3650);
DISPLAY 0.787234 (-1700 3650);
PAINT MONO (-1700 3650);
DISPLAY INVISIBLE (-1700 3650);
FORCEPROP 1 LAST BODY_TYPE PLUMBING
J 2
(-1700 3600);
DISPLAY 1.234043 (-1700 3600);
PAINT GREEN (-1700 3600);
DISPLAY INVISIBLE (-1700 3600);
FORCEPROP 1 LAST HDL_TAP TRUE
J 2
(-2025 3525);
DISPLAY 1.234043 (-2025 3525);
PAINT GREEN (-2025 3525);
DISPLAY INVISIBLE (-2025 3525);
FORCEPROP 1 LAST PATH I67
J 2
(-1700 3650);
DISPLAY 0.936170 (-1700 3650);
PAINT GREEN (-1700 3650);
DISPLAY INVISIBLE (-1700 3650);
FORCEADD TAP..6
R 2
(-1700 3600);
FORCEPROP 3 LASTPIN (-1750 3600) SIG_NAME M_C_DQ<43>
J 0
(-1740 3610);
DISPLAY 0.659574 (-1740 3610);
PAINT MONO (-1740 3610);
DISPLAY INVISIBLE (-1740 3610);
FORCEPROP 1 LASTPIN (-1750 3600) BN 43
J 2
(-1700 3610);
DISPLAY 0.617021 (-1700 3610);
PAINT PINK (-1700 3610);
FORCEPROP 2 LAST CDS_LIB mstr_standard
J 2
(-1700 3600);
DISPLAY 0.787234 (-1700 3600);
PAINT MONO (-1700 3600);
DISPLAY INVISIBLE (-1700 3600);
FORCEPROP 1 LAST BODY_TYPE PLUMBING
J 2
(-1700 3550);
DISPLAY 1.234043 (-1700 3550);
PAINT GREEN (-1700 3550);
DISPLAY INVISIBLE (-1700 3550);
FORCEPROP 1 LAST HDL_TAP TRUE
J 2
(-2025 3475);
DISPLAY 1.234043 (-2025 3475);
PAINT GREEN (-2025 3475);
DISPLAY INVISIBLE (-2025 3475);
FORCEPROP 1 LAST PATH I68
J 2
(-1700 3600);
DISPLAY 0.936170 (-1700 3600);
PAINT GREEN (-1700 3600);
DISPLAY INVISIBLE (-1700 3600);
FORCEADD TAP..6
R 2
(-1700 3550);
FORCEPROP 3 LASTPIN (-1750 3550) SIG_NAME M_C_DQ<40>
J 0
(-1740 3560);
DISPLAY 0.659574 (-1740 3560);
PAINT MONO (-1740 3560);
DISPLAY INVISIBLE (-1740 3560);
FORCEPROP 1 LASTPIN (-1750 3550) BN 40
J 2
(-1700 3560);
DISPLAY 0.617021 (-1700 3560);
PAINT PINK (-1700 3560);
FORCEPROP 2 LAST CDS_LIB mstr_standard
J 2
(-1700 3550);
DISPLAY 0.787234 (-1700 3550);
PAINT MONO (-1700 3550);
DISPLAY INVISIBLE (-1700 3550);
FORCEPROP 1 LAST BODY_TYPE PLUMBING
J 2
(-1700 3500);
DISPLAY 1.234043 (-1700 3500);
PAINT GREEN (-1700 3500);
DISPLAY INVISIBLE (-1700 3500);
FORCEPROP 1 LAST HDL_TAP TRUE
J 2
(-2025 3425);
DISPLAY 1.234043 (-2025 3425);
PAINT GREEN (-2025 3425);
DISPLAY INVISIBLE (-2025 3425);
FORCEPROP 1 LAST PATH I69
J 2
(-1700 3550);
DISPLAY 0.936170 (-1700 3550);
PAINT GREEN (-1700 3550);
DISPLAY INVISIBLE (-1700 3550);
FORCEADD TAP..6
R 2
(900 5050);
FORCEPROP 3 LASTPIN (850 5050) SIG_NAME M_C_DQS_DN<16>
J 0
(860 5060);
DISPLAY 0.659574 (860 5060);
PAINT MONO (860 5060);
DISPLAY INVISIBLE (860 5060);
FORCEPROP 1 LASTPIN (850 5050) BN 16
J 2
(900 5060);
DISPLAY 0.617021 (900 5060);
PAINT PINK (900 5060);
FORCEPROP 2 LAST CDS_LIB mstr_standard
J 0
(900 5050);
DISPLAY 0.787234 (900 5050);
PAINT MONO (900 5050);
DISPLAY INVISIBLE (900 5050);
FORCEPROP 1 LAST BODY_TYPE PLUMBING
J 2
(900 5000);
DISPLAY 1.234043 (900 5000);
PAINT GREEN (900 5000);
DISPLAY INVISIBLE (900 5000);
FORCEPROP 1 LAST HDL_TAP TRUE
J 2
(575 4925);
DISPLAY 1.234043 (575 4925);
PAINT GREEN (575 4925);
DISPLAY INVISIBLE (575 4925);
FORCEPROP 1 LAST PATH I7
J 2
(900 5050);
DISPLAY 0.936170 (900 5050);
PAINT GREEN (900 5050);
DISPLAY INVISIBLE (900 5050);
FORCEADD TAP..6
R 2
(-1700 3450);
FORCEPROP 3 LASTPIN (-1750 3450) SIG_NAME M_C_DQ<38>
J 0
(-1740 3460);
DISPLAY 0.659574 (-1740 3460);
PAINT MONO (-1740 3460);
DISPLAY INVISIBLE (-1740 3460);
FORCEPROP 1 LASTPIN (-1750 3450) BN 38
J 2
(-1700 3460);
DISPLAY 0.617021 (-1700 3460);
PAINT PINK (-1700 3460);
FORCEPROP 2 LAST CDS_LIB mstr_standard
J 2
(-1700 3450);
DISPLAY 0.787234 (-1700 3450);
PAINT MONO (-1700 3450);
DISPLAY INVISIBLE (-1700 3450);
FORCEPROP 1 LAST BODY_TYPE PLUMBING
J 2
(-1700 3400);
DISPLAY 1.234043 (-1700 3400);
PAINT GREEN (-1700 3400);
DISPLAY INVISIBLE (-1700 3400);
FORCEPROP 1 LAST HDL_TAP TRUE
J 2
(-2025 3325);
DISPLAY 1.234043 (-2025 3325);
PAINT GREEN (-2025 3325);
DISPLAY INVISIBLE (-2025 3325);
FORCEPROP 1 LAST PATH I70
J 2
(-1700 3450);
DISPLAY 0.936170 (-1700 3450);
PAINT GREEN (-1700 3450);
DISPLAY INVISIBLE (-1700 3450);
FORCEADD TAP..6
R 2
(-1700 3500);
FORCEPROP 3 LASTPIN (-1750 3500) SIG_NAME M_C_DQ<41>
J 0
(-1740 3510);
DISPLAY 0.659574 (-1740 3510);
PAINT MONO (-1740 3510);
DISPLAY INVISIBLE (-1740 3510);
FORCEPROP 1 LASTPIN (-1750 3500) BN 41
J 2
(-1700 3510);
DISPLAY 0.617021 (-1700 3510);
PAINT PINK (-1700 3510);
FORCEPROP 2 LAST CDS_LIB mstr_standard
J 2
(-1700 3500);
DISPLAY 0.787234 (-1700 3500);
PAINT MONO (-1700 3500);
DISPLAY INVISIBLE (-1700 3500);
FORCEPROP 1 LAST BODY_TYPE PLUMBING
J 2
(-1700 3450);
DISPLAY 1.234043 (-1700 3450);
PAINT GREEN (-1700 3450);
DISPLAY INVISIBLE (-1700 3450);
FORCEPROP 1 LAST HDL_TAP TRUE
J 2
(-2025 3375);
DISPLAY 1.234043 (-2025 3375);
PAINT GREEN (-2025 3375);
DISPLAY INVISIBLE (-2025 3375);
FORCEPROP 1 LAST PATH I71
J 2
(-1700 3500);
DISPLAY 0.936170 (-1700 3500);
PAINT GREEN (-1700 3500);
DISPLAY INVISIBLE (-1700 3500);
FORCEADD TAP..6
R 2
(-1700 3300);
FORCEPROP 3 LASTPIN (-1750 3300) SIG_NAME M_C_DQ<37>
J 0
(-1740 3310);
DISPLAY 0.659574 (-1740 3310);
PAINT MONO (-1740 3310);
DISPLAY INVISIBLE (-1740 3310);
FORCEPROP 1 LASTPIN (-1750 3300) BN 37
J 2
(-1700 3310);
DISPLAY 0.617021 (-1700 3310);
PAINT PINK (-1700 3310);
FORCEPROP 2 LAST CDS_LIB mstr_standard
J 2
(-1700 3300);
DISPLAY 0.787234 (-1700 3300);
PAINT MONO (-1700 3300);
DISPLAY INVISIBLE (-1700 3300);
FORCEPROP 1 LAST BODY_TYPE PLUMBING
J 2
(-1700 3250);
DISPLAY 1.234043 (-1700 3250);
PAINT GREEN (-1700 3250);
DISPLAY INVISIBLE (-1700 3250);
FORCEPROP 1 LAST HDL_TAP TRUE
J 2
(-2025 3175);
DISPLAY 1.234043 (-2025 3175);
PAINT GREEN (-2025 3175);
DISPLAY INVISIBLE (-2025 3175);
FORCEPROP 1 LAST PATH I72
J 2
(-1700 3300);
DISPLAY 0.936170 (-1700 3300);
PAINT GREEN (-1700 3300);
DISPLAY INVISIBLE (-1700 3300);
FORCEADD TAP..6
R 2
(-1700 3350);
FORCEPROP 3 LASTPIN (-1750 3350) SIG_NAME M_C_DQ<36>
J 0
(-1740 3360);
DISPLAY 0.659574 (-1740 3360);
PAINT MONO (-1740 3360);
DISPLAY INVISIBLE (-1740 3360);
FORCEPROP 1 LASTPIN (-1750 3350) BN 36
J 2
(-1700 3360);
DISPLAY 0.617021 (-1700 3360);
PAINT PINK (-1700 3360);
FORCEPROP 2 LAST CDS_LIB mstr_standard
J 2
(-1700 3350);
DISPLAY 0.787234 (-1700 3350);
PAINT MONO (-1700 3350);
DISPLAY INVISIBLE (-1700 3350);
FORCEPROP 1 LAST BODY_TYPE PLUMBING
J 2
(-1700 3300);
DISPLAY 1.234043 (-1700 3300);
PAINT GREEN (-1700 3300);
DISPLAY INVISIBLE (-1700 3300);
FORCEPROP 1 LAST HDL_TAP TRUE
J 2
(-2025 3225);
DISPLAY 1.234043 (-2025 3225);
PAINT GREEN (-2025 3225);
DISPLAY INVISIBLE (-2025 3225);
FORCEPROP 1 LAST PATH I73
J 2
(-1700 3350);
DISPLAY 0.936170 (-1700 3350);
PAINT GREEN (-1700 3350);
DISPLAY INVISIBLE (-1700 3350);
FORCEADD TAP..6
R 2
(-1700 3400);
FORCEPROP 3 LASTPIN (-1750 3400) SIG_NAME M_C_DQ<39>
J 0
(-1740 3410);
DISPLAY 0.659574 (-1740 3410);
PAINT MONO (-1740 3410);
DISPLAY INVISIBLE (-1740 3410);
FORCEPROP 1 LASTPIN (-1750 3400) BN 39
J 2
(-1700 3410);
DISPLAY 0.617021 (-1700 3410);
PAINT PINK (-1700 3410);
FORCEPROP 2 LAST CDS_LIB mstr_standard
J 2
(-1700 3400);
DISPLAY 0.787234 (-1700 3400);
PAINT MONO (-1700 3400);
DISPLAY INVISIBLE (-1700 3400);
FORCEPROP 1 LAST BODY_TYPE PLUMBING
J 2
(-1700 3350);
DISPLAY 1.234043 (-1700 3350);
PAINT GREEN (-1700 3350);
DISPLAY INVISIBLE (-1700 3350);
FORCEPROP 1 LAST HDL_TAP TRUE
J 2
(-2025 3275);
DISPLAY 1.234043 (-2025 3275);
PAINT GREEN (-2025 3275);
DISPLAY INVISIBLE (-2025 3275);
FORCEPROP 1 LAST PATH I74
J 2
(-1700 3400);
DISPLAY 0.936170 (-1700 3400);
PAINT GREEN (-1700 3400);
DISPLAY INVISIBLE (-1700 3400);
FORCEADD TAP..6
R 2
(-1700 3200);
FORCEPROP 3 LASTPIN (-1750 3200) SIG_NAME M_C_DQ<35>
J 0
(-1740 3210);
DISPLAY 0.659574 (-1740 3210);
PAINT MONO (-1740 3210);
DISPLAY INVISIBLE (-1740 3210);
FORCEPROP 1 LASTPIN (-1750 3200) BN 35
J 2
(-1700 3210);
DISPLAY 0.617021 (-1700 3210);
PAINT PINK (-1700 3210);
FORCEPROP 2 LAST CDS_LIB mstr_standard
J 2
(-1700 3200);
DISPLAY 0.787234 (-1700 3200);
PAINT MONO (-1700 3200);
DISPLAY INVISIBLE (-1700 3200);
FORCEPROP 1 LAST BODY_TYPE PLUMBING
J 2
(-1700 3150);
DISPLAY 1.234043 (-1700 3150);
PAINT GREEN (-1700 3150);
DISPLAY INVISIBLE (-1700 3150);
FORCEPROP 1 LAST HDL_TAP TRUE
J 2
(-2025 3075);
DISPLAY 1.234043 (-2025 3075);
PAINT GREEN (-2025 3075);
DISPLAY INVISIBLE (-2025 3075);
FORCEPROP 1 LAST PATH I75
J 2
(-1700 3200);
DISPLAY 0.936170 (-1700 3200);
PAINT GREEN (-1700 3200);
DISPLAY INVISIBLE (-1700 3200);
FORCEADD TAP..6
R 2
(-1700 3250);
FORCEPROP 3 LASTPIN (-1750 3250) SIG_NAME M_C_DQ<34>
J 0
(-1740 3260);
DISPLAY 0.659574 (-1740 3260);
PAINT MONO (-1740 3260);
DISPLAY INVISIBLE (-1740 3260);
FORCEPROP 1 LASTPIN (-1750 3250) BN 34
J 2
(-1700 3260);
DISPLAY 0.617021 (-1700 3260);
PAINT PINK (-1700 3260);
FORCEPROP 2 LAST CDS_LIB mstr_standard
J 2
(-1700 3250);
DISPLAY 0.787234 (-1700 3250);
PAINT MONO (-1700 3250);
DISPLAY INVISIBLE (-1700 3250);
FORCEPROP 1 LAST BODY_TYPE PLUMBING
J 2
(-1700 3200);
DISPLAY 1.234043 (-1700 3200);
PAINT GREEN (-1700 3200);
DISPLAY INVISIBLE (-1700 3200);
FORCEPROP 1 LAST HDL_TAP TRUE
J 2
(-2025 3125);
DISPLAY 1.234043 (-2025 3125);
PAINT GREEN (-2025 3125);
DISPLAY INVISIBLE (-2025 3125);
FORCEPROP 1 LAST PATH I76
J 2
(-1700 3250);
DISPLAY 0.936170 (-1700 3250);
PAINT GREEN (-1700 3250);
DISPLAY INVISIBLE (-1700 3250);
FORCEADD TAP..6
R 2
(-1700 3150);
FORCEPROP 3 LASTPIN (-1750 3150) SIG_NAME M_C_DQ<32>
J 0
(-1740 3160);
DISPLAY 0.659574 (-1740 3160);
PAINT MONO (-1740 3160);
DISPLAY INVISIBLE (-1740 3160);
FORCEPROP 1 LASTPIN (-1750 3150) BN 32
J 2
(-1700 3160);
DISPLAY 0.617021 (-1700 3160);
PAINT PINK (-1700 3160);
FORCEPROP 2 LAST CDS_LIB mstr_standard
J 2
(-1700 3150);
DISPLAY 0.787234 (-1700 3150);
PAINT MONO (-1700 3150);
DISPLAY INVISIBLE (-1700 3150);
FORCEPROP 1 LAST BODY_TYPE PLUMBING
J 2
(-1700 3100);
DISPLAY 1.234043 (-1700 3100);
PAINT GREEN (-1700 3100);
DISPLAY INVISIBLE (-1700 3100);
FORCEPROP 1 LAST HDL_TAP TRUE
J 2
(-2025 3025);
DISPLAY 1.234043 (-2025 3025);
PAINT GREEN (-2025 3025);
DISPLAY INVISIBLE (-2025 3025);
FORCEPROP 1 LAST PATH I77
J 2
(-1700 3150);
DISPLAY 0.936170 (-1700 3150);
PAINT GREEN (-1700 3150);
DISPLAY INVISIBLE (-1700 3150);
FORCEADD TAP..6
R 2
(-1700 3100);
FORCEPROP 3 LASTPIN (-1750 3100) SIG_NAME M_C_DQ<33>
J 0
(-1740 3110);
DISPLAY 0.659574 (-1740 3110);
PAINT MONO (-1740 3110);
DISPLAY INVISIBLE (-1740 3110);
FORCEPROP 1 LASTPIN (-1750 3100) BN 33
J 2
(-1700 3110);
DISPLAY 0.617021 (-1700 3110);
PAINT PINK (-1700 3110);
FORCEPROP 2 LAST CDS_LIB mstr_standard
J 2
(-1700 3100);
DISPLAY 0.787234 (-1700 3100);
PAINT MONO (-1700 3100);
DISPLAY INVISIBLE (-1700 3100);
FORCEPROP 1 LAST BODY_TYPE PLUMBING
J 2
(-1700 3050);
DISPLAY 1.234043 (-1700 3050);
PAINT GREEN (-1700 3050);
DISPLAY INVISIBLE (-1700 3050);
FORCEPROP 1 LAST HDL_TAP TRUE
J 2
(-2025 2975);
DISPLAY 1.234043 (-2025 2975);
PAINT GREEN (-2025 2975);
DISPLAY INVISIBLE (-2025 2975);
FORCEPROP 1 LAST PATH I78
J 2
(-1700 3100);
DISPLAY 0.936170 (-1700 3100);
PAINT GREEN (-1700 3100);
DISPLAY INVISIBLE (-1700 3100);
FORCEADD TAP..6
R 2
(-1700 3050);
FORCEPROP 3 LASTPIN (-1750 3050) SIG_NAME M_C_DQ<30>
J 0
(-1740 3060);
DISPLAY 0.659574 (-1740 3060);
PAINT MONO (-1740 3060);
DISPLAY INVISIBLE (-1740 3060);
FORCEPROP 1 LASTPIN (-1750 3050) BN 30
J 2
(-1700 3060);
DISPLAY 0.617021 (-1700 3060);
PAINT PINK (-1700 3060);
FORCEPROP 2 LAST CDS_LIB mstr_standard
J 2
(-1700 3050);
DISPLAY 0.787234 (-1700 3050);
PAINT MONO (-1700 3050);
DISPLAY INVISIBLE (-1700 3050);
FORCEPROP 1 LAST BODY_TYPE PLUMBING
J 2
(-1700 3000);
DISPLAY 1.234043 (-1700 3000);
PAINT GREEN (-1700 3000);
DISPLAY INVISIBLE (-1700 3000);
FORCEPROP 1 LAST HDL_TAP TRUE
J 2
(-2025 2925);
DISPLAY 1.234043 (-2025 2925);
PAINT GREEN (-2025 2925);
DISPLAY INVISIBLE (-2025 2925);
FORCEPROP 1 LAST PATH I79
J 2
(-1700 3050);
DISPLAY 0.936170 (-1700 3050);
PAINT GREEN (-1700 3050);
DISPLAY INVISIBLE (-1700 3050);
FORCEADD TAP..6
R 2
(900 4850);
FORCEPROP 3 LASTPIN (850 4850) SIG_NAME M_C_DQS_DN<14>
J 0
(860 4860);
DISPLAY 0.659574 (860 4860);
PAINT MONO (860 4860);
DISPLAY INVISIBLE (860 4860);
FORCEPROP 1 LASTPIN (850 4850) BN 14
J 2
(900 4860);
DISPLAY 0.617021 (900 4860);
PAINT PINK (900 4860);
FORCEPROP 2 LAST CDS_LIB mstr_standard
J 0
(900 4850);
DISPLAY 0.787234 (900 4850);
PAINT MONO (900 4850);
DISPLAY INVISIBLE (900 4850);
FORCEPROP 1 LAST BODY_TYPE PLUMBING
J 2
(900 4800);
DISPLAY 1.234043 (900 4800);
PAINT GREEN (900 4800);
DISPLAY INVISIBLE (900 4800);
FORCEPROP 1 LAST HDL_TAP TRUE
J 2
(575 4725);
DISPLAY 1.234043 (575 4725);
PAINT GREEN (575 4725);
DISPLAY INVISIBLE (575 4725);
FORCEPROP 1 LAST PATH I8
J 2
(900 4850);
DISPLAY 0.936170 (900 4850);
PAINT GREEN (900 4850);
DISPLAY INVISIBLE (900 4850);
FORCEADD TAP..6
R 2
(-1700 2900);
FORCEPROP 3 LASTPIN (-1750 2900) SIG_NAME M_C_DQ<29>
J 0
(-1740 2910);
DISPLAY 0.659574 (-1740 2910);
PAINT MONO (-1740 2910);
DISPLAY INVISIBLE (-1740 2910);
FORCEPROP 1 LASTPIN (-1750 2900) BN 29
J 2
(-1700 2910);
DISPLAY 0.617021 (-1700 2910);
PAINT PINK (-1700 2910);
FORCEPROP 2 LAST CDS_LIB mstr_standard
J 2
(-1700 2900);
DISPLAY 0.787234 (-1700 2900);
PAINT MONO (-1700 2900);
DISPLAY INVISIBLE (-1700 2900);
FORCEPROP 1 LAST BODY_TYPE PLUMBING
J 2
(-1700 2850);
DISPLAY 1.234043 (-1700 2850);
PAINT GREEN (-1700 2850);
DISPLAY INVISIBLE (-1700 2850);
FORCEPROP 1 LAST HDL_TAP TRUE
J 2
(-2025 2775);
DISPLAY 1.234043 (-2025 2775);
PAINT GREEN (-2025 2775);
DISPLAY INVISIBLE (-2025 2775);
FORCEPROP 1 LAST PATH I80
J 2
(-1700 2900);
DISPLAY 0.936170 (-1700 2900);
PAINT GREEN (-1700 2900);
DISPLAY INVISIBLE (-1700 2900);
FORCEADD TAP..6
R 2
(-1700 2950);
FORCEPROP 3 LASTPIN (-1750 2950) SIG_NAME M_C_DQ<28>
J 0
(-1740 2960);
DISPLAY 0.659574 (-1740 2960);
PAINT MONO (-1740 2960);
DISPLAY INVISIBLE (-1740 2960);
FORCEPROP 1 LASTPIN (-1750 2950) BN 28
J 2
(-1700 2960);
DISPLAY 0.617021 (-1700 2960);
PAINT PINK (-1700 2960);
FORCEPROP 2 LAST CDS_LIB mstr_standard
J 2
(-1700 2950);
DISPLAY 0.787234 (-1700 2950);
PAINT MONO (-1700 2950);
DISPLAY INVISIBLE (-1700 2950);
FORCEPROP 1 LAST BODY_TYPE PLUMBING
J 2
(-1700 2900);
DISPLAY 1.234043 (-1700 2900);
PAINT GREEN (-1700 2900);
DISPLAY INVISIBLE (-1700 2900);
FORCEPROP 1 LAST HDL_TAP TRUE
J 2
(-2025 2825);
DISPLAY 1.234043 (-2025 2825);
PAINT GREEN (-2025 2825);
DISPLAY INVISIBLE (-2025 2825);
FORCEPROP 1 LAST PATH I81
J 2
(-1700 2950);
DISPLAY 0.936170 (-1700 2950);
PAINT GREEN (-1700 2950);
DISPLAY INVISIBLE (-1700 2950);
FORCEADD TAP..6
R 2
(-1700 3000);
FORCEPROP 3 LASTPIN (-1750 3000) SIG_NAME M_C_DQ<31>
J 0
(-1740 3010);
DISPLAY 0.659574 (-1740 3010);
PAINT MONO (-1740 3010);
DISPLAY INVISIBLE (-1740 3010);
FORCEPROP 1 LASTPIN (-1750 3000) BN 31
J 2
(-1700 3010);
DISPLAY 0.617021 (-1700 3010);
PAINT PINK (-1700 3010);
FORCEPROP 2 LAST CDS_LIB mstr_standard
J 2
(-1700 3000);
DISPLAY 0.787234 (-1700 3000);
PAINT MONO (-1700 3000);
DISPLAY INVISIBLE (-1700 3000);
FORCEPROP 1 LAST BODY_TYPE PLUMBING
J 2
(-1700 2950);
DISPLAY 1.234043 (-1700 2950);
PAINT GREEN (-1700 2950);
DISPLAY INVISIBLE (-1700 2950);
FORCEPROP 1 LAST HDL_TAP TRUE
J 2
(-2025 2875);
DISPLAY 1.234043 (-2025 2875);
PAINT GREEN (-2025 2875);
DISPLAY INVISIBLE (-2025 2875);
FORCEPROP 1 LAST PATH I82
J 2
(-1700 3000);
DISPLAY 0.936170 (-1700 3000);
PAINT GREEN (-1700 3000);
DISPLAY INVISIBLE (-1700 3000);
FORCEADD TAP..6
R 2
(-1700 2850);
FORCEPROP 3 LASTPIN (-1750 2850) SIG_NAME M_C_DQ<26>
J 0
(-1740 2860);
DISPLAY 0.659574 (-1740 2860);
PAINT MONO (-1740 2860);
DISPLAY INVISIBLE (-1740 2860);
FORCEPROP 1 LASTPIN (-1750 2850) BN 26
J 2
(-1700 2860);
DISPLAY 0.617021 (-1700 2860);
PAINT PINK (-1700 2860);
FORCEPROP 2 LAST CDS_LIB mstr_standard
J 2
(-1700 2850);
DISPLAY 0.787234 (-1700 2850);
PAINT MONO (-1700 2850);
DISPLAY INVISIBLE (-1700 2850);
FORCEPROP 1 LAST BODY_TYPE PLUMBING
J 2
(-1700 2800);
DISPLAY 1.234043 (-1700 2800);
PAINT GREEN (-1700 2800);
DISPLAY INVISIBLE (-1700 2800);
FORCEPROP 1 LAST HDL_TAP TRUE
J 2
(-2025 2725);
DISPLAY 1.234043 (-2025 2725);
PAINT GREEN (-2025 2725);
DISPLAY INVISIBLE (-2025 2725);
FORCEPROP 1 LAST PATH I83
J 2
(-1700 2850);
DISPLAY 0.936170 (-1700 2850);
PAINT GREEN (-1700 2850);
DISPLAY INVISIBLE (-1700 2850);
FORCEADD TAP..6
R 2
(-1700 2800);
FORCEPROP 3 LASTPIN (-1750 2800) SIG_NAME M_C_DQ<27>
J 0
(-1740 2810);
DISPLAY 0.659574 (-1740 2810);
PAINT MONO (-1740 2810);
DISPLAY INVISIBLE (-1740 2810);
FORCEPROP 1 LASTPIN (-1750 2800) BN 27
J 2
(-1700 2810);
DISPLAY 0.617021 (-1700 2810);
PAINT PINK (-1700 2810);
FORCEPROP 2 LAST CDS_LIB mstr_standard
J 2
(-1700 2800);
DISPLAY 0.787234 (-1700 2800);
PAINT MONO (-1700 2800);
DISPLAY INVISIBLE (-1700 2800);
FORCEPROP 1 LAST BODY_TYPE PLUMBING
J 2
(-1700 2750);
DISPLAY 1.234043 (-1700 2750);
PAINT GREEN (-1700 2750);
DISPLAY INVISIBLE (-1700 2750);
FORCEPROP 1 LAST HDL_TAP TRUE
J 2
(-2025 2675);
DISPLAY 1.234043 (-2025 2675);
PAINT GREEN (-2025 2675);
DISPLAY INVISIBLE (-2025 2675);
FORCEPROP 1 LAST PATH I84
J 2
(-1700 2800);
DISPLAY 0.936170 (-1700 2800);
PAINT GREEN (-1700 2800);
DISPLAY INVISIBLE (-1700 2800);
FORCEADD TAP..6
R 2
(-1700 2650);
FORCEPROP 3 LASTPIN (-1750 2650) SIG_NAME M_C_DQ<22>
J 0
(-1740 2660);
DISPLAY 0.659574 (-1740 2660);
PAINT MONO (-1740 2660);
DISPLAY INVISIBLE (-1740 2660);
FORCEPROP 1 LASTPIN (-1750 2650) BN 22
J 2
(-1700 2660);
DISPLAY 0.617021 (-1700 2660);
PAINT PINK (-1700 2660);
FORCEPROP 2 LAST CDS_LIB mstr_standard
J 2
(-1700 2650);
DISPLAY 0.787234 (-1700 2650);
PAINT MONO (-1700 2650);
DISPLAY INVISIBLE (-1700 2650);
FORCEPROP 1 LAST BODY_TYPE PLUMBING
J 2
(-1700 2600);
DISPLAY 1.234043 (-1700 2600);
PAINT GREEN (-1700 2600);
DISPLAY INVISIBLE (-1700 2600);
FORCEPROP 1 LAST HDL_TAP TRUE
J 2
(-2025 2525);
DISPLAY 1.234043 (-2025 2525);
PAINT GREEN (-2025 2525);
DISPLAY INVISIBLE (-2025 2525);
FORCEPROP 1 LAST PATH I85
J 2
(-1700 2650);
DISPLAY 0.936170 (-1700 2650);
PAINT GREEN (-1700 2650);
DISPLAY INVISIBLE (-1700 2650);
FORCEADD TAP..6
R 2
(-1700 2750);
FORCEPROP 3 LASTPIN (-1750 2750) SIG_NAME M_C_DQ<24>
J 0
(-1740 2760);
DISPLAY 0.659574 (-1740 2760);
PAINT MONO (-1740 2760);
DISPLAY INVISIBLE (-1740 2760);
FORCEPROP 1 LASTPIN (-1750 2750) BN 24
J 2
(-1700 2760);
DISPLAY 0.617021 (-1700 2760);
PAINT PINK (-1700 2760);
FORCEPROP 2 LAST CDS_LIB mstr_standard
J 2
(-1700 2750);
DISPLAY 0.787234 (-1700 2750);
PAINT MONO (-1700 2750);
DISPLAY INVISIBLE (-1700 2750);
FORCEPROP 1 LAST BODY_TYPE PLUMBING
J 2
(-1700 2700);
DISPLAY 1.234043 (-1700 2700);
PAINT GREEN (-1700 2700);
DISPLAY INVISIBLE (-1700 2700);
FORCEPROP 1 LAST HDL_TAP TRUE
J 2
(-2025 2625);
DISPLAY 1.234043 (-2025 2625);
PAINT GREEN (-2025 2625);
DISPLAY INVISIBLE (-2025 2625);
FORCEPROP 1 LAST PATH I86
J 2
(-1700 2750);
DISPLAY 0.936170 (-1700 2750);
PAINT GREEN (-1700 2750);
DISPLAY INVISIBLE (-1700 2750);
FORCEADD TAP..6
R 2
(-1700 2700);
FORCEPROP 3 LASTPIN (-1750 2700) SIG_NAME M_C_DQ<25>
J 0
(-1740 2710);
DISPLAY 0.659574 (-1740 2710);
PAINT MONO (-1740 2710);
DISPLAY INVISIBLE (-1740 2710);
FORCEPROP 1 LASTPIN (-1750 2700) BN 25
J 2
(-1700 2710);
DISPLAY 0.617021 (-1700 2710);
PAINT PINK (-1700 2710);
FORCEPROP 2 LAST CDS_LIB mstr_standard
J 2
(-1700 2700);
DISPLAY 0.787234 (-1700 2700);
PAINT MONO (-1700 2700);
DISPLAY INVISIBLE (-1700 2700);
FORCEPROP 1 LAST BODY_TYPE PLUMBING
J 2
(-1700 2650);
DISPLAY 1.234043 (-1700 2650);
PAINT GREEN (-1700 2650);
DISPLAY INVISIBLE (-1700 2650);
FORCEPROP 1 LAST HDL_TAP TRUE
J 2
(-2025 2575);
DISPLAY 1.234043 (-2025 2575);
PAINT GREEN (-2025 2575);
DISPLAY INVISIBLE (-2025 2575);
FORCEPROP 1 LAST PATH I87
J 2
(-1700 2700);
DISPLAY 0.936170 (-1700 2700);
PAINT GREEN (-1700 2700);
DISPLAY INVISIBLE (-1700 2700);
FORCEADD TAP..6
R 2
(-1700 2550);
FORCEPROP 3 LASTPIN (-1750 2550) SIG_NAME M_C_DQ<20>
J 0
(-1740 2560);
DISPLAY 0.659574 (-1740 2560);
PAINT MONO (-1740 2560);
DISPLAY INVISIBLE (-1740 2560);
FORCEPROP 1 LASTPIN (-1750 2550) BN 20
J 2
(-1700 2560);
DISPLAY 0.617021 (-1700 2560);
PAINT PINK (-1700 2560);
FORCEPROP 2 LAST CDS_LIB mstr_standard
J 2
(-1700 2550);
DISPLAY 0.787234 (-1700 2550);
PAINT MONO (-1700 2550);
DISPLAY INVISIBLE (-1700 2550);
FORCEPROP 1 LAST BODY_TYPE PLUMBING
J 2
(-1700 2500);
DISPLAY 1.234043 (-1700 2500);
PAINT GREEN (-1700 2500);
DISPLAY INVISIBLE (-1700 2500);
FORCEPROP 1 LAST HDL_TAP TRUE
J 2
(-2025 2425);
DISPLAY 1.234043 (-2025 2425);
PAINT GREEN (-2025 2425);
DISPLAY INVISIBLE (-2025 2425);
FORCEPROP 1 LAST PATH I88
J 2
(-1700 2550);
DISPLAY 0.936170 (-1700 2550);
PAINT GREEN (-1700 2550);
DISPLAY INVISIBLE (-1700 2550);
FORCEADD TAP..6
R 2
(-1700 2600);
FORCEPROP 3 LASTPIN (-1750 2600) SIG_NAME M_C_DQ<23>
J 0
(-1740 2610);
DISPLAY 0.659574 (-1740 2610);
PAINT MONO (-1740 2610);
DISPLAY INVISIBLE (-1740 2610);
FORCEPROP 1 LASTPIN (-1750 2600) BN 23
J 2
(-1700 2610);
DISPLAY 0.617021 (-1700 2610);
PAINT PINK (-1700 2610);
FORCEPROP 2 LAST CDS_LIB mstr_standard
J 2
(-1700 2600);
DISPLAY 0.787234 (-1700 2600);
PAINT MONO (-1700 2600);
DISPLAY INVISIBLE (-1700 2600);
FORCEPROP 1 LAST BODY_TYPE PLUMBING
J 2
(-1700 2550);
DISPLAY 1.234043 (-1700 2550);
PAINT GREEN (-1700 2550);
DISPLAY INVISIBLE (-1700 2550);
FORCEPROP 1 LAST HDL_TAP TRUE
J 2
(-2025 2475);
DISPLAY 1.234043 (-2025 2475);
PAINT GREEN (-2025 2475);
DISPLAY INVISIBLE (-2025 2475);
FORCEPROP 1 LAST PATH I89
J 2
(-1700 2600);
DISPLAY 0.936170 (-1700 2600);
PAINT GREEN (-1700 2600);
DISPLAY INVISIBLE (-1700 2600);
FORCEADD TAP..6
R 2
(700 5000);
FORCEPROP 3 LASTPIN (650 5000) SIG_NAME M_C_DQS_DP<15>
J 0
(660 5010);
DISPLAY 0.659574 (660 5010);
PAINT MONO (660 5010);
DISPLAY INVISIBLE (660 5010);
FORCEPROP 1 LASTPIN (650 5000) BN 15
J 2
(700 5010);
DISPLAY 0.617021 (700 5010);
PAINT PINK (700 5010);
FORCEPROP 2 LAST CDS_LIB mstr_standard
J 0
(700 5000);
DISPLAY 0.787234 (700 5000);
PAINT MONO (700 5000);
DISPLAY INVISIBLE (700 5000);
FORCEPROP 1 LAST BODY_TYPE PLUMBING
J 2
(700 4950);
DISPLAY 1.234043 (700 4950);
PAINT GREEN (700 4950);
DISPLAY INVISIBLE (700 4950);
FORCEPROP 1 LAST HDL_TAP TRUE
J 2
(375 4875);
DISPLAY 1.234043 (375 4875);
PAINT GREEN (375 4875);
DISPLAY INVISIBLE (375 4875);
FORCEPROP 1 LAST PATH I9
J 2
(700 5000);
DISPLAY 0.936170 (700 5000);
PAINT GREEN (700 5000);
DISPLAY INVISIBLE (700 5000);
FORCEADD TAP..6
R 2
(-1700 2500);
FORCEPROP 3 LASTPIN (-1750 2500) SIG_NAME M_C_DQ<21>
J 0
(-1740 2510);
DISPLAY 0.659574 (-1740 2510);
PAINT MONO (-1740 2510);
DISPLAY INVISIBLE (-1740 2510);
FORCEPROP 1 LASTPIN (-1750 2500) BN 21
J 2
(-1700 2510);
DISPLAY 0.617021 (-1700 2510);
PAINT PINK (-1700 2510);
FORCEPROP 2 LAST CDS_LIB mstr_standard
J 2
(-1700 2500);
DISPLAY 0.787234 (-1700 2500);
PAINT MONO (-1700 2500);
DISPLAY INVISIBLE (-1700 2500);
FORCEPROP 1 LAST BODY_TYPE PLUMBING
J 2
(-1700 2450);
DISPLAY 1.234043 (-1700 2450);
PAINT GREEN (-1700 2450);
DISPLAY INVISIBLE (-1700 2450);
FORCEPROP 1 LAST HDL_TAP TRUE
J 2
(-2025 2375);
DISPLAY 1.234043 (-2025 2375);
PAINT GREEN (-2025 2375);
DISPLAY INVISIBLE (-2025 2375);
FORCEPROP 1 LAST PATH I90
J 2
(-1700 2500);
DISPLAY 0.936170 (-1700 2500);
PAINT GREEN (-1700 2500);
DISPLAY INVISIBLE (-1700 2500);
FORCEADD TAP..6
R 2
(-1700 2450);
FORCEPROP 3 LASTPIN (-1750 2450) SIG_NAME M_C_DQ<18>
J 0
(-1740 2460);
DISPLAY 0.659574 (-1740 2460);
PAINT MONO (-1740 2460);
DISPLAY INVISIBLE (-1740 2460);
FORCEPROP 1 LASTPIN (-1750 2450) BN 18
J 2
(-1700 2460);
DISPLAY 0.617021 (-1700 2460);
PAINT PINK (-1700 2460);
FORCEPROP 2 LAST CDS_LIB mstr_standard
J 2
(-1700 2450);
DISPLAY 0.787234 (-1700 2450);
PAINT MONO (-1700 2450);
DISPLAY INVISIBLE (-1700 2450);
FORCEPROP 1 LAST BODY_TYPE PLUMBING
J 2
(-1700 2400);
DISPLAY 1.234043 (-1700 2400);
PAINT GREEN (-1700 2400);
DISPLAY INVISIBLE (-1700 2400);
FORCEPROP 1 LAST HDL_TAP TRUE
J 2
(-2025 2325);
DISPLAY 1.234043 (-2025 2325);
PAINT GREEN (-2025 2325);
DISPLAY INVISIBLE (-2025 2325);
FORCEPROP 1 LAST PATH I91
J 2
(-1700 2450);
DISPLAY 0.936170 (-1700 2450);
PAINT GREEN (-1700 2450);
DISPLAY INVISIBLE (-1700 2450);
FORCEADD TAP..6
R 2
(-1700 2400);
FORCEPROP 3 LASTPIN (-1750 2400) SIG_NAME M_C_DQ<19>
J 0
(-1740 2410);
DISPLAY 0.659574 (-1740 2410);
PAINT MONO (-1740 2410);
DISPLAY INVISIBLE (-1740 2410);
FORCEPROP 1 LASTPIN (-1750 2400) BN 19
J 2
(-1700 2410);
DISPLAY 0.617021 (-1700 2410);
PAINT PINK (-1700 2410);
FORCEPROP 2 LAST CDS_LIB mstr_standard
J 2
(-1700 2400);
DISPLAY 0.787234 (-1700 2400);
PAINT MONO (-1700 2400);
DISPLAY INVISIBLE (-1700 2400);
FORCEPROP 1 LAST BODY_TYPE PLUMBING
J 2
(-1700 2350);
DISPLAY 1.234043 (-1700 2350);
PAINT GREEN (-1700 2350);
DISPLAY INVISIBLE (-1700 2350);
FORCEPROP 1 LAST HDL_TAP TRUE
J 2
(-2025 2275);
DISPLAY 1.234043 (-2025 2275);
PAINT GREEN (-2025 2275);
DISPLAY INVISIBLE (-2025 2275);
FORCEPROP 1 LAST PATH I92
J 2
(-1700 2400);
DISPLAY 0.936170 (-1700 2400);
PAINT GREEN (-1700 2400);
DISPLAY INVISIBLE (-1700 2400);
FORCEADD TAP..6
R 2
(-1700 2300);
FORCEPROP 3 LASTPIN (-1750 2300) SIG_NAME M_C_DQ<17>
J 0
(-1740 2310);
DISPLAY 0.659574 (-1740 2310);
PAINT MONO (-1740 2310);
DISPLAY INVISIBLE (-1740 2310);
FORCEPROP 1 LASTPIN (-1750 2300) BN 17
J 2
(-1700 2310);
DISPLAY 0.617021 (-1700 2310);
PAINT PINK (-1700 2310);
FORCEPROP 2 LAST CDS_LIB mstr_standard
J 2
(-1700 2300);
DISPLAY 0.787234 (-1700 2300);
PAINT MONO (-1700 2300);
DISPLAY INVISIBLE (-1700 2300);
FORCEPROP 1 LAST BODY_TYPE PLUMBING
J 2
(-1700 2250);
DISPLAY 1.234043 (-1700 2250);
PAINT GREEN (-1700 2250);
DISPLAY INVISIBLE (-1700 2250);
FORCEPROP 1 LAST HDL_TAP TRUE
J 2
(-2025 2175);
DISPLAY 1.234043 (-2025 2175);
PAINT GREEN (-2025 2175);
DISPLAY INVISIBLE (-2025 2175);
FORCEPROP 1 LAST PATH I93
J 2
(-1700 2300);
DISPLAY 0.936170 (-1700 2300);
PAINT GREEN (-1700 2300);
DISPLAY INVISIBLE (-1700 2300);
FORCEADD TAP..6
R 2
(-1700 2350);
FORCEPROP 3 LASTPIN (-1750 2350) SIG_NAME M_C_DQ<16>
J 0
(-1740 2360);
DISPLAY 0.659574 (-1740 2360);
PAINT MONO (-1740 2360);
DISPLAY INVISIBLE (-1740 2360);
FORCEPROP 1 LASTPIN (-1750 2350) BN 16
J 2
(-1700 2360);
DISPLAY 0.617021 (-1700 2360);
PAINT PINK (-1700 2360);
FORCEPROP 2 LAST CDS_LIB mstr_standard
J 2
(-1700 2350);
DISPLAY 0.787234 (-1700 2350);
PAINT MONO (-1700 2350);
DISPLAY INVISIBLE (-1700 2350);
FORCEPROP 1 LAST BODY_TYPE PLUMBING
J 2
(-1700 2300);
DISPLAY 1.234043 (-1700 2300);
PAINT GREEN (-1700 2300);
DISPLAY INVISIBLE (-1700 2300);
FORCEPROP 1 LAST HDL_TAP TRUE
J 2
(-2025 2225);
DISPLAY 1.234043 (-2025 2225);
PAINT GREEN (-2025 2225);
DISPLAY INVISIBLE (-2025 2225);
FORCEPROP 1 LAST PATH I94
J 2
(-1700 2350);
DISPLAY 0.936170 (-1700 2350);
PAINT GREEN (-1700 2350);
DISPLAY INVISIBLE (-1700 2350);
FORCEADD TAP..6
R 2
(-1700 2150);
FORCEPROP 3 LASTPIN (-1750 2150) SIG_NAME M_C_DQ<12>
J 0
(-1740 2160);
DISPLAY 0.659574 (-1740 2160);
PAINT MONO (-1740 2160);
DISPLAY INVISIBLE (-1740 2160);
FORCEPROP 1 LASTPIN (-1750 2150) BN 12
J 2
(-1700 2160);
DISPLAY 0.617021 (-1700 2160);
PAINT PINK (-1700 2160);
FORCEPROP 2 LAST CDS_LIB mstr_standard
J 2
(-1700 2150);
DISPLAY 0.787234 (-1700 2150);
PAINT MONO (-1700 2150);
DISPLAY INVISIBLE (-1700 2150);
FORCEPROP 1 LAST BODY_TYPE PLUMBING
J 2
(-1700 2100);
DISPLAY 1.234043 (-1700 2100);
PAINT GREEN (-1700 2100);
DISPLAY INVISIBLE (-1700 2100);
FORCEPROP 1 LAST HDL_TAP TRUE
J 2
(-2025 2025);
DISPLAY 1.234043 (-2025 2025);
PAINT GREEN (-2025 2025);
DISPLAY INVISIBLE (-2025 2025);
FORCEPROP 1 LAST PATH I95
J 2
(-1700 2150);
DISPLAY 0.936170 (-1700 2150);
PAINT GREEN (-1700 2150);
DISPLAY INVISIBLE (-1700 2150);
FORCEADD TAP..6
R 2
(-1700 2200);
FORCEPROP 3 LASTPIN (-1750 2200) SIG_NAME M_C_DQ<15>
J 0
(-1740 2210);
DISPLAY 0.659574 (-1740 2210);
PAINT MONO (-1740 2210);
DISPLAY INVISIBLE (-1740 2210);
FORCEPROP 1 LASTPIN (-1750 2200) BN 15
J 2
(-1700 2210);
DISPLAY 0.617021 (-1700 2210);
PAINT PINK (-1700 2210);
FORCEPROP 2 LAST CDS_LIB mstr_standard
J 2
(-1700 2200);
DISPLAY 0.787234 (-1700 2200);
PAINT MONO (-1700 2200);
DISPLAY INVISIBLE (-1700 2200);
FORCEPROP 1 LAST BODY_TYPE PLUMBING
J 2
(-1700 2150);
DISPLAY 1.234043 (-1700 2150);
PAINT GREEN (-1700 2150);
DISPLAY INVISIBLE (-1700 2150);
FORCEPROP 1 LAST HDL_TAP TRUE
J 2
(-2025 2075);
DISPLAY 1.234043 (-2025 2075);
PAINT GREEN (-2025 2075);
DISPLAY INVISIBLE (-2025 2075);
FORCEPROP 1 LAST PATH I96
J 2
(-1700 2200);
DISPLAY 0.936170 (-1700 2200);
PAINT GREEN (-1700 2200);
DISPLAY INVISIBLE (-1700 2200);
FORCEADD TAP..6
R 2
(-1700 2250);
FORCEPROP 3 LASTPIN (-1750 2250) SIG_NAME M_C_DQ<14>
J 0
(-1740 2260);
DISPLAY 0.659574 (-1740 2260);
PAINT MONO (-1740 2260);
DISPLAY INVISIBLE (-1740 2260);
FORCEPROP 1 LASTPIN (-1750 2250) BN 14
J 2
(-1700 2260);
DISPLAY 0.617021 (-1700 2260);
PAINT PINK (-1700 2260);
FORCEPROP 2 LAST CDS_LIB mstr_standard
J 2
(-1700 2250);
DISPLAY 0.787234 (-1700 2250);
PAINT MONO (-1700 2250);
DISPLAY INVISIBLE (-1700 2250);
FORCEPROP 1 LAST BODY_TYPE PLUMBING
J 2
(-1700 2200);
DISPLAY 1.234043 (-1700 2200);
PAINT GREEN (-1700 2200);
DISPLAY INVISIBLE (-1700 2200);
FORCEPROP 1 LAST HDL_TAP TRUE
J 2
(-2025 2125);
DISPLAY 1.234043 (-2025 2125);
PAINT GREEN (-2025 2125);
DISPLAY INVISIBLE (-2025 2125);
FORCEPROP 1 LAST PATH I97
J 2
(-1700 2250);
DISPLAY 0.936170 (-1700 2250);
PAINT GREEN (-1700 2250);
DISPLAY INVISIBLE (-1700 2250);
FORCEADD TAP..6
R 2
(-1700 2050);
FORCEPROP 3 LASTPIN (-1750 2050) SIG_NAME M_C_DQ<10>
J 0
(-1740 2060);
DISPLAY 0.659574 (-1740 2060);
PAINT MONO (-1740 2060);
DISPLAY INVISIBLE (-1740 2060);
FORCEPROP 1 LASTPIN (-1750 2050) BN 10
J 2
(-1700 2060);
DISPLAY 0.617021 (-1700 2060);
PAINT PINK (-1700 2060);
FORCEPROP 2 LAST CDS_LIB mstr_standard
J 2
(-1700 2050);
DISPLAY 0.787234 (-1700 2050);
PAINT MONO (-1700 2050);
DISPLAY INVISIBLE (-1700 2050);
FORCEPROP 1 LAST BODY_TYPE PLUMBING
J 2
(-1700 2000);
DISPLAY 1.234043 (-1700 2000);
PAINT GREEN (-1700 2000);
DISPLAY INVISIBLE (-1700 2000);
FORCEPROP 1 LAST HDL_TAP TRUE
J 2
(-2025 1925);
DISPLAY 1.234043 (-2025 1925);
PAINT GREEN (-2025 1925);
DISPLAY INVISIBLE (-2025 1925);
FORCEPROP 1 LAST PATH I98
J 2
(-1700 2050);
DISPLAY 0.936170 (-1700 2050);
PAINT GREEN (-1700 2050);
DISPLAY INVISIBLE (-1700 2050);
FORCEADD TAP..6
R 2
(-1700 2100);
FORCEPROP 3 LASTPIN (-1750 2100) SIG_NAME M_C_DQ<13>
J 0
(-1740 2110);
DISPLAY 0.659574 (-1740 2110);
PAINT MONO (-1740 2110);
DISPLAY INVISIBLE (-1740 2110);
FORCEPROP 1 LASTPIN (-1750 2100) BN 13
J 2
(-1700 2110);
DISPLAY 0.617021 (-1700 2110);
PAINT PINK (-1700 2110);
FORCEPROP 2 LAST CDS_LIB mstr_standard
J 2
(-1700 2100);
DISPLAY 0.787234 (-1700 2100);
PAINT MONO (-1700 2100);
DISPLAY INVISIBLE (-1700 2100);
FORCEPROP 1 LAST BODY_TYPE PLUMBING
J 2
(-1700 2050);
DISPLAY 1.234043 (-1700 2050);
PAINT GREEN (-1700 2050);
DISPLAY INVISIBLE (-1700 2050);
FORCEPROP 1 LAST HDL_TAP TRUE
J 2
(-2025 1975);
DISPLAY 1.234043 (-2025 1975);
PAINT GREEN (-2025 1975);
DISPLAY INVISIBLE (-2025 1975);
FORCEPROP 1 LAST PATH I99
J 2
(-1700 2100);
DISPLAY 0.936170 (-1700 2100);
PAINT GREEN (-1700 2100);
DISPLAY INVISIBLE (-1700 2100);
FORCEADD INTEL_CORP_BPAGE..1
(2650 500);
FORCEPROP 1 LAST CDS_CON_LAST_MODIFIED Fri Jun 16 17:48:18 2017
J 0
(1225 825);
DISPLAY 0.787234 (1225 825);
PAINT ORANGE (1225 825);
DISPLAY INVISIBLE (1225 825);
FORCEPROP 1 LAST CUSTOM_TXT_CDS <CURRENT_DESIGN_SHEET> OF <TOTAL_DESIGN_SHEETS>
J 0
(2150 525);
PAINT ORANGE (2150 525);
FORCEPROP 1 LAST CUSTOM_TXT_CDS <CON_LAST_MODIFIED>
J 0
(-1350 600);
PAINT ORANGE (-1350 600);
FORCEPROP 2 LAST CUSTOM_TXT_CDS <XR_PAGE_TITLE>
J 0
(-5240 5750);
DISPLAY 0.638298 (-5240 5750);
PAINT PINK (-5240 5750);
DISPLAY INVISIBLE (-5240 5750);
FORCEPROP 1 LAST SCH_TITLE CPU0 DDR4 CH C DIMM0
J 0
(-5300 550);
DISPLAY 1.212766 (-5300 550);
PAINT WHITE (-5300 550);
FORCEPROP 2 LAST PAGE_BORDER TRUE
J 0
(-5240 5750);
DISPLAY 0.680851 (-5240 5750);
PAINT PINK (-5240 5750);
DISPLAY INVISIBLE (-5240 5750);
FORCEPROP 2 LAST CDS_LIB mstr_symbols
J 0
(2650 500);
DISPLAY 0.787234 (2650 500);
PAINT MONO (2650 500);
DISPLAY INVISIBLE (2650 500);
FORCEPROP 1 LAST COMMENT_BODY TRUE
J 0
(2660 510);
DISPLAY 0.382979 (2660 510);
PAINT GREEN (2660 510);
DISPLAY INVISIBLE (2660 510);
FORCEPROP 2 LAST CDS_XR_PAGE_TITLE CR-47 : @BASEBOARD_FAB2_LIB.BASEBOARD_FAB2(SCH_1):PAGE47
J 0
(-5240 5750);
DISPLAY 0.638298 (-5240 5750);
PAINT PINK (-5240 5750);
DISPLAY INVISIBLE (-5240 5750);
FORCEADD BOM_NOTE..1
(-4975 5275);
FORCEPROP 0 LAST L1 STUFF FOR SKU A & B
J 0
(-5125 5175);
DISPLAY 1.063830 (-5125 5175);
PAINT WHITE (-5125 5175);
FORCEPROP 2 LAST CDS_LIB mstr_symbols
J 0
(-4975 5275);
PAINT ORANGE (-4975 5275);
DISPLAY INVISIBLE (-4975 5275);
FORCEPROP 2 LAST BOM_COST SB
J 0
(-5125 5250);
DISPLAY 1.361702 (-5125 5250);
PAINT ORANGE (-5125 5250);
DISPLAY INVISIBLE (-5125 5250);
FORCEPROP 1 LAST COMMENT_BODY TRUE
J 0
(-4950 5375);
DISPLAY 1.319149 (-4950 5375);
PAINT ORANGE (-4950 5375);
DISPLAY INVISIBLE (-4950 5375);
FORCEPROP 2 LAST ROOM SB_HEADERS
J 0
(-5125 5250);
DISPLAY 1.361702 (-5125 5250);
PAINT ORANGE (-5125 5250);
DISPLAY INVISIBLE (-5125 5250);
WIRE 16 -1 (-850 2650)(-850 2550);
WIRE 16 -1 (-850 2550)(-700 2550);
WIRE 16 -1 (-700 2550)(-700 2600);
WIRE 16 -1 (-700 2550)(-500 2550);
WIRE 16 -1 (-700 2600)(-500 2600);
WIRE 16 -1 (-1150 2550)(-1150 2450);
WIRE 16 -1 (-700 2450)(-1150 2450);
WIRE 16 -1 (-700 2450)(-700 2400);
WIRE 16 -1 (-700 2450)(-500 2450);
WIRE 16 -1 (-700 2400)(-700 2350);
WIRE 16 -1 (-700 2400)(-500 2400);
WIRE 16 -1 (-700 2350)(-700 2300);
WIRE 16 -1 (-700 2350)(-500 2350);
WIRE 16 -1 (-700 2300)(-700 2250);
WIRE 16 -1 (-700 2300)(-500 2300);
WIRE 16 -1 (-700 2250)(-700 2200);
WIRE 16 -1 (-700 2250)(-500 2250);
WIRE 16 -1 (-700 2200)(-700 2150);
WIRE 16 -1 (-700 2200)(-500 2200);
WIRE 16 -1 (-700 2150)(-700 2100);
WIRE 16 -1 (-700 2150)(-500 2150);
WIRE 16 -1 (-700 2100)(-700 2050);
WIRE 16 -1 (-700 2100)(-500 2100);
WIRE 16 -1 (-700 2050)(-700 2000);
WIRE 16 -1 (-700 2050)(-500 2050);
WIRE 16 -1 (-700 2000)(-700 1950);
WIRE 16 -1 (-700 2000)(-500 2000);
WIRE 16 -1 (-700 1950)(-700 1900);
WIRE 16 -1 (-700 1950)(-500 1950);
WIRE 16 -1 (-700 1900)(-700 1850);
WIRE 16 -1 (-700 1900)(-500 1900);
WIRE 16 -1 (-700 1850)(-700 1800);
WIRE 16 -1 (-700 1850)(-500 1850);
WIRE 16 -1 (-700 1800)(-700 1750);
WIRE 16 -1 (-700 1800)(-500 1800);
WIRE 16 -1 (-700 1750)(-700 1700);
WIRE 16 -1 (-700 1750)(-500 1750);
WIRE 16 -1 (-700 1700)(-700 1650);
WIRE 16 -1 (-700 1700)(-500 1700);
WIRE 16 -1 (-700 1650)(-700 1600);
WIRE 16 -1 (-700 1650)(-500 1650);
WIRE 16 -1 (-700 1600)(-700 1550);
WIRE 16 -1 (-700 1600)(-500 1600);
WIRE 16 -1 (-700 1550)(-700 1500);
WIRE 16 -1 (-700 1550)(-500 1550);
WIRE 16 -1 (-700 1500)(-700 1450);
WIRE 16 -1 (-700 1500)(-500 1500);
WIRE 16 -1 (-700 1450)(-700 1400);
WIRE 16 -1 (-700 1450)(-500 1450);
WIRE 16 -1 (-700 1400)(-700 1350);
WIRE 16 -1 (-700 1400)(-500 1400);
WIRE 16 -1 (-700 1350)(-700 1300);
WIRE 16 -1 (-700 1350)(-500 1350);
WIRE 16 -1 (-700 1300)(-700 1250);
WIRE 16 -1 (-700 1300)(-500 1300);
WIRE 16 -1 (-700 1250)(-700 1200);
WIRE 16 -1 (-700 1250)(-500 1250);
WIRE 16 -1 (-700 1200)(-500 1200);
WIRE 16 -1 (2500 1500)(2500 1400);
WIRE 16 -1 (2500 1500)(2500 1550);
WIRE 16 -1 (2500 1500)(2300 1500);
WIRE 16 -1 (2500 1550)(2500 1600);
WIRE 16 -1 (2500 1550)(2300 1550);
WIRE 16 -1 (2500 1600)(2500 1650);
WIRE 16 -1 (2500 1600)(2300 1600);
WIRE 16 -1 (2500 1650)(2500 1700);
WIRE 16 -1 (2500 1650)(2300 1650);
WIRE 16 -1 (2500 1700)(2500 1750);
WIRE 16 -1 (2500 1700)(2300 1700);
WIRE 16 -1 (2500 1750)(2500 1800);
WIRE 16 -1 (2500 1750)(2300 1750);
WIRE 16 -1 (2500 1800)(2500 1850);
WIRE 16 -1 (2500 1800)(2300 1800);
WIRE 16 -1 (2500 1850)(2500 1900);
WIRE 16 -1 (2500 1850)(2300 1850);
WIRE 16 -1 (2500 1900)(2500 1950);
WIRE 16 -1 (2500 1900)(2300 1900);
WIRE 16 -1 (2500 1950)(2500 2000);
WIRE 16 -1 (2500 1950)(2300 1950);
WIRE 16 -1 (2500 2000)(2500 2050);
WIRE 16 -1 (2500 2000)(2300 2000);
WIRE 16 -1 (2500 2050)(2500 2100);
WIRE 16 -1 (2500 2050)(2300 2050);
WIRE 16 -1 (2500 2100)(2500 2150);
WIRE 16 -1 (2500 2100)(2300 2100);
WIRE 16 -1 (2500 2150)(2500 2200);
WIRE 16 -1 (2500 2150)(2300 2150);
WIRE 16 -1 (2500 2200)(2500 2250);
WIRE 16 -1 (2500 2200)(2300 2200);
WIRE 16 -1 (2500 2250)(2500 2300);
WIRE 16 -1 (2500 2250)(2300 2250);
WIRE 16 -1 (2500 2300)(2500 2350);
WIRE 16 -1 (2500 2300)(2300 2300);
WIRE 16 -1 (2500 2350)(2500 2400);
WIRE 16 -1 (2500 2350)(2300 2350);
WIRE 16 -1 (2500 2400)(2500 2450);
WIRE 16 -1 (2500 2400)(2300 2400);
WIRE 16 -1 (2500 2450)(2500 2500);
WIRE 16 -1 (2500 2450)(2300 2450);
WIRE 16 -1 (2500 2500)(2500 2550);
WIRE 16 -1 (2500 2500)(2300 2500);
WIRE 16 -1 (2500 2550)(2500 2600);
WIRE 16 -1 (2500 2550)(2300 2550);
WIRE 16 -1 (2500 2600)(2500 2650);
WIRE 16 -1 (2500 2600)(2300 2600);
WIRE 16 -1 (2500 2650)(2500 2700);
WIRE 16 -1 (2500 2650)(2300 2650);
WIRE 16 -1 (2500 2700)(2500 2750);
WIRE 16 -1 (2500 2700)(2300 2700);
WIRE 16 -1 (2500 2750)(2500 2800);
WIRE 16 -1 (2500 2750)(2300 2750);
WIRE 16 -1 (2500 2800)(2500 2850);
WIRE 16 -1 (2500 2800)(2300 2800);
WIRE 16 -1 (2500 2850)(2500 2900);
WIRE 16 -1 (2500 2850)(2300 2850);
WIRE 16 -1 (2500 2900)(2500 2950);
WIRE 16 -1 (2500 2900)(2300 2900);
WIRE 16 -1 (2500 2950)(2500 3000);
WIRE 16 -1 (2500 2950)(2300 2950);
WIRE 16 -1 (2500 3000)(2500 3050);
WIRE 16 -1 (2500 3000)(2300 3000);
WIRE 16 -1 (2500 3050)(2500 3100);
WIRE 16 -1 (2500 3050)(2300 3050);
WIRE 16 -1 (2500 3100)(2500 3150);
WIRE 16 -1 (2500 3100)(2300 3100);
WIRE 16 -1 (2500 3150)(2500 3200);
WIRE 16 -1 (2500 3150)(2300 3150);
WIRE 16 -1 (2500 3200)(2500 3250);
WIRE 16 -1 (2500 3200)(2300 3200);
WIRE 16 -1 (2500 3250)(2500 3300);
WIRE 16 -1 (2500 3250)(2300 3250);
WIRE 16 -1 (2500 3300)(2500 3350);
WIRE 16 -1 (2500 3300)(2300 3300);
WIRE 16 -1 (2500 3350)(2500 3400);
WIRE 16 -1 (2500 3350)(2300 3350);
WIRE 16 -1 (2500 3400)(2500 3450);
WIRE 16 -1 (2500 3400)(2300 3400);
WIRE 16 -1 (2500 3450)(2500 3500);
WIRE 16 -1 (2500 3450)(2300 3450);
WIRE 16 -1 (2500 3500)(2500 3550);
WIRE 16 -1 (2500 3500)(2300 3500);
WIRE 16 -1 (2500 3550)(2500 3600);
WIRE 16 -1 (2500 3550)(2300 3550);
WIRE 16 -1 (2500 3600)(2500 3650);
WIRE 16 -1 (2500 3600)(2300 3600);
WIRE 16 -1 (2500 3650)(2500 3700);
WIRE 16 -1 (2500 3650)(2300 3650);
WIRE 16 -1 (2500 3700)(2500 3750);
WIRE 16 -1 (2500 3700)(2300 3700);
WIRE 16 -1 (2500 3800)(2500 3750);
WIRE 16 -1 (2500 3750)(2300 3750);
WIRE 16 -1 (2500 3800)(2300 3800);
WIRE 16 -1 (-4950 1750)(-4950 1700);
WIRE 16 -1 (-3300 1750)(-4950 1750);
WIRE 16 -1 (-3300 1750)(-3300 1700);
WIRE 16 -1 (-2950 1750)(-3300 1750);
WIRE 16 -1 (-2950 1700)(-3300 1700);
WIRE 16 -1 (-4650 1200)(-4650 1100);
WIRE 16 -1 (-700 3000)(-700 2900);
WIRE 16 -1 (-700 2900)(-700 2850);
WIRE 16 -1 (-700 2900)(-500 2900);
WIRE 16 -1 (-700 2850)(-700 2800);
WIRE 16 -1 (-700 2850)(-500 2850);
WIRE 16 -1 (-700 2800)(-700 2750);
WIRE 16 -1 (-700 2800)(-500 2800);
WIRE 16 -1 (-700 2750)(-700 2700);
WIRE 16 -1 (-700 2750)(-500 2750);
WIRE 16 -1 (-700 2700)(-500 2700);
WIRE 16 -1 (-4950 1950)(-4950 1850);
WIRE 16 -1 (-4950 1850)(-3300 1850);
WIRE 16 -1 (-3300 1800)(-3300 1850);
WIRE 16 -1 (-3300 1850)(-2950 1850);
WIRE 16 -1 (-2950 1800)(-3300 1800);
WIRE 16 -1 (700 2900)(700 3075);
WIRE 16 -1 (700 2850)(700 2900);
WIRE 16 -1 (500 2900)(700 2900);
WIRE 16 -1 (500 2850)(700 2850);
WIRE 16 -1 (1100 1500)(1100 1400);
WIRE 16 -1 (1100 1500)(1100 1550);
WIRE 16 -1 (1100 1500)(1300 1500);
WIRE 16 -1 (1100 1550)(1100 1600);
WIRE 16 -1 (1100 1550)(1300 1550);
WIRE 16 -1 (1100 1600)(1100 1650);
WIRE 16 -1 (1100 1600)(1300 1600);
WIRE 16 -1 (1100 1650)(1100 1700);
WIRE 16 -1 (1100 1650)(1300 1650);
WIRE 16 -1 (1100 1700)(1100 1750);
WIRE 16 -1 (1100 1700)(1300 1700);
WIRE 16 -1 (1100 1750)(1100 1800);
WIRE 16 -1 (1100 1750)(1300 1750);
WIRE 16 -1 (1100 1800)(1100 1850);
WIRE 16 -1 (1100 1800)(1300 1800);
WIRE 16 -1 (1100 1850)(1100 1900);
WIRE 16 -1 (1100 1850)(1300 1850);
WIRE 16 -1 (1100 1900)(1100 1950);
WIRE 16 -1 (1100 1900)(1300 1900);
WIRE 16 -1 (1100 1950)(1100 2000);
WIRE 16 -1 (1100 1950)(1300 1950);
WIRE 16 -1 (1100 2000)(1100 2050);
WIRE 16 -1 (1100 2000)(1300 2000);
WIRE 16 -1 (1100 2050)(1100 2100);
WIRE 16 -1 (1100 2050)(1300 2050);
WIRE 16 -1 (1100 2100)(1100 2150);
WIRE 16 -1 (1100 2100)(1300 2100);
WIRE 16 -1 (1100 2150)(1100 2200);
WIRE 16 -1 (1100 2150)(1300 2150);
WIRE 16 -1 (1100 2200)(1100 2250);
WIRE 16 -1 (1100 2200)(1300 2200);
WIRE 16 -1 (1100 2250)(1100 2300);
WIRE 16 -1 (1100 2250)(1300 2250);
WIRE 16 -1 (1100 2300)(1100 2350);
WIRE 16 -1 (1100 2300)(1300 2300);
WIRE 16 -1 (1100 2350)(1100 2400);
WIRE 16 -1 (1100 2350)(1300 2350);
WIRE 16 -1 (1100 2400)(1100 2450);
WIRE 16 -1 (1100 2400)(1300 2400);
WIRE 16 -1 (1100 2450)(1100 2500);
WIRE 16 -1 (1100 2450)(1300 2450);
WIRE 16 -1 (1100 2500)(1100 2550);
WIRE 16 -1 (1100 2500)(1300 2500);
WIRE 16 -1 (1100 2550)(1100 2600);
WIRE 16 -1 (1100 2550)(1300 2550);
WIRE 16 -1 (1100 2600)(1100 2650);
WIRE 16 -1 (1100 2600)(1300 2600);
WIRE 16 -1 (1100 2650)(1100 2700);
WIRE 16 -1 (1100 2650)(1300 2650);
WIRE 16 -1 (1100 2700)(1100 2750);
WIRE 16 -1 (1100 2700)(1300 2700);
WIRE 16 -1 (1100 2750)(1100 2800);
WIRE 16 -1 (1100 2750)(1300 2750);
WIRE 16 -1 (1100 2800)(1100 2850);
WIRE 16 -1 (1100 2800)(1300 2800);
WIRE 16 -1 (1100 2850)(1100 2900);
WIRE 16 -1 (1100 2850)(1300 2850);
WIRE 16 -1 (1100 2900)(1100 2950);
WIRE 16 -1 (1100 2900)(1300 2900);
WIRE 16 -1 (1100 2950)(1100 3000);
WIRE 16 -1 (1100 2950)(1300 2950);
WIRE 16 -1 (1100 3000)(1100 3050);
WIRE 16 -1 (1100 3000)(1300 3000);
WIRE 16 -1 (1100 3050)(1100 3100);
WIRE 16 -1 (1100 3050)(1300 3050);
WIRE 16 -1 (1100 3100)(1100 3150);
WIRE 16 -1 (1100 3100)(1300 3100);
WIRE 16 -1 (1100 3150)(1100 3200);
WIRE 16 -1 (1100 3150)(1300 3150);
WIRE 16 -1 (1100 3200)(1100 3250);
WIRE 16 -1 (1100 3200)(1300 3200);
WIRE 16 -1 (1100 3250)(1100 3300);
WIRE 16 -1 (1100 3250)(1300 3250);
WIRE 16 -1 (1100 3300)(1100 3350);
WIRE 16 -1 (1100 3300)(1300 3300);
WIRE 16 -1 (1100 3350)(1100 3400);
WIRE 16 -1 (1100 3350)(1300 3350);
WIRE 16 -1 (1100 3400)(1100 3450);
WIRE 16 -1 (1100 3400)(1300 3400);
WIRE 16 -1 (1100 3450)(1100 3500);
WIRE 16 -1 (1100 3450)(1300 3450);
WIRE 16 -1 (1100 3500)(1100 3550);
WIRE 16 -1 (1100 3500)(1300 3500);
WIRE 16 -1 (1100 3550)(1100 3600);
WIRE 16 -1 (1100 3550)(1300 3550);
WIRE 16 -1 (1100 3600)(1100 3650);
WIRE 16 -1 (1100 3600)(1300 3600);
WIRE 16 -1 (1100 3650)(1100 3700);
WIRE 16 -1 (1100 3650)(1300 3650);
WIRE 16 -1 (1100 3700)(1100 3750);
WIRE 16 -1 (1100 3700)(1300 3700);
WIRE 16 -1 (1100 3800)(1100 3750);
WIRE 16 -1 (1100 3750)(1300 3750);
WIRE 16 -1 (1100 3800)(1300 3800);
WIRE 17 -1 (950 3475)(950 3575);
WIRE 17 -1 (950 3575)(950 3675);
WIRE 17 -1 (950 3675)(950 3775);
WIRE 17 -1 (950 3775)(950 3875);
WIRE 17 -1 (950 3875)(950 3975);
WIRE 17 -1 (950 3975)(950 4075);
WIRE 17 -1 (950 4075)(950 4175);
WIRE 17 -1 (950 4175)(950 4275);
WIRE 17 -1 (950 4275)(950 4375);
WIRE 17 -1 (950 4375)(950 4475);
WIRE 17 -1 (950 4475)(950 4575);
WIRE 17 -1 (950 4575)(950 4675);
WIRE 17 -1 (950 4675)(950 4775);
WIRE 17 -1 (950 4775)(950 4875);
WIRE 17 -1 (950 4875)(950 4975);
WIRE 17 -1 (950 4975)(950 5075);
WIRE 17 -1 (1550 5200)(950 5200);
FORCEPROP 2 LAST SIG_NAME M_C_DQS_DN<17:0>
J 0
(1000 5210);
DISPLAY 0.617021 (1000 5210);
PAINT ORANGE (1000 5210);
WIRE 17 -1 (950 5075)(950 5175);
WIRE 17 -1 (950 5175)(950 5200);
WIRE 17 -1 (750 3525)(750 3625);
WIRE 17 -1 (750 3625)(750 3725);
WIRE 17 -1 (750 3725)(750 3825);
WIRE 17 -1 (750 3825)(750 3925);
WIRE 17 -1 (750 3925)(750 4025);
WIRE 17 -1 (750 4025)(750 4125);
WIRE 17 -1 (750 4125)(750 4225);
WIRE 17 -1 (750 4225)(750 4325);
WIRE 17 -1 (750 4325)(750 4425);
WIRE 17 -1 (750 4425)(750 4525);
WIRE 17 -1 (750 4525)(750 4625);
WIRE 17 -1 (750 4625)(750 4725);
WIRE 17 -1 (750 4725)(750 4825);
WIRE 17 -1 (750 4825)(750 4925);
WIRE 17 -1 (750 4925)(750 5025);
WIRE 17 -1 (750 5025)(750 5125);
WIRE 17 -1 (1550 5250)(750 5250);
FORCEPROP 2 LAST SIG_NAME M_C_DQS_DP<17:0>
J 0
(1000 5260);
DISPLAY 0.617021 (1000 5260);
PAINT ORANGE (1000 5260);
WIRE 17 -1 (750 5125)(750 5225);
WIRE 17 -1 (750 5225)(750 5250);
WIRE 17 -1 (-1650 1525)(-1650 1575);
WIRE 17 -1 (-1650 1575)(-1650 1625);
WIRE 17 -1 (-1650 1625)(-1650 1675);
WIRE 17 -1 (-1650 1675)(-1650 1725);
WIRE 17 -1 (-1650 1725)(-1650 1775);
WIRE 17 -1 (-1650 1775)(-1650 1825);
WIRE 17 -1 (-1650 1825)(-1650 1875);
WIRE 17 -1 (-1650 1875)(-1650 1925);
WIRE 17 -1 (-1650 1925)(-1650 1975);
WIRE 17 -1 (-1650 1975)(-1650 2025);
WIRE 17 -1 (-1650 2025)(-1650 2075);
WIRE 17 -1 (-1650 2075)(-1650 2125);
WIRE 17 -1 (-1650 2125)(-1650 2175);
WIRE 17 -1 (-1650 2175)(-1650 2225);
WIRE 17 -1 (-1650 2225)(-1650 2275);
WIRE 17 -1 (-1650 2275)(-1650 2325);
WIRE 17 -1 (-1650 2325)(-1650 2375);
WIRE 17 -1 (-1650 2375)(-1650 2425);
WIRE 17 -1 (-1650 2425)(-1650 2475);
WIRE 17 -1 (-1650 2475)(-1650 2525);
WIRE 17 -1 (-1650 2525)(-1650 2575);
WIRE 17 -1 (-1650 2575)(-1650 2625);
WIRE 17 -1 (-1650 2625)(-1650 2675);
WIRE 17 -1 (-1650 2675)(-1650 2725);
WIRE 17 -1 (-1650 2725)(-1650 2775);
WIRE 17 -1 (-1650 2775)(-1650 2825);
WIRE 17 -1 (-1650 2825)(-1650 2875);
WIRE 17 -1 (-1650 2875)(-1650 2925);
WIRE 17 -1 (-1650 2925)(-1650 2975);
WIRE 17 -1 (-1650 2975)(-1650 3025);
WIRE 17 -1 (-1650 3025)(-1650 3075);
WIRE 17 -1 (-1650 3075)(-1650 3125);
WIRE 17 -1 (-1650 3125)(-1650 3175);
WIRE 17 -1 (-1650 3175)(-1650 3225);
WIRE 17 -1 (-1650 3225)(-1650 3275);
WIRE 17 -1 (-1650 3275)(-1650 3325);
WIRE 17 -1 (-1650 3325)(-1650 3375);
WIRE 17 -1 (-1650 3375)(-1650 3425);
WIRE 17 -1 (-1650 3425)(-1650 3475);
WIRE 17 -1 (-1650 3475)(-1650 3525);
WIRE 17 -1 (-1650 3525)(-1650 3575);
WIRE 17 -1 (-1650 3575)(-1650 3625);
WIRE 17 -1 (-1650 3625)(-1650 3675);
WIRE 17 -1 (-1650 3675)(-1650 3725);
WIRE 17 -1 (-1650 3725)(-1650 3775);
WIRE 17 -1 (-1650 3775)(-1650 3825);
WIRE 17 -1 (-1650 3825)(-1650 3875);
WIRE 17 -1 (-1650 3875)(-1650 3925);
WIRE 17 -1 (-1650 3925)(-1650 3975);
WIRE 17 -1 (-1650 3975)(-1650 4025);
WIRE 17 -1 (-1650 4025)(-1650 4075);
WIRE 17 -1 (-1650 4075)(-1650 4125);
WIRE 17 -1 (-1650 4125)(-1650 4175);
WIRE 17 -1 (-1650 4175)(-1650 4225);
WIRE 17 -1 (-1650 4225)(-1650 4275);
WIRE 17 -1 (-1650 4275)(-1650 4325);
WIRE 17 -1 (-1650 4325)(-1650 4375);
WIRE 17 -1 (-1650 4375)(-1650 4425);
WIRE 17 -1 (-1650 4425)(-1650 4475);
WIRE 17 -1 (-1650 4475)(-1650 4525);
WIRE 17 -1 (-1650 4525)(-1650 4575);
WIRE 17 -1 (-1650 4575)(-1650 4625);
WIRE 17 -1 (-1200 4700)(-1650 4700);
FORCEPROP 2 LAST SIG_NAME M_C_DQ<63:0>
J 0
(-1610 4710);
DISPLAY 0.617021 (-1610 4710);
PAINT ORANGE (-1610 4710);
WIRE 17 -1 (-1650 4625)(-1650 4675);
WIRE 17 -1 (-1650 4675)(-1650 4700);
WIRE 17 -1 (-3250 3825)(-3250 3875);
WIRE 17 -1 (-3250 3875)(-3250 3925);
WIRE 17 -1 (-3250 3925)(-3250 3975);
WIRE 17 -1 (-3250 3975)(-3250 4025);
WIRE 17 -1 (-3750 4700)(-3250 4700);
FORCEPROP 2 LAST SIG_NAME M_C_MA<17:0>
J 0
(-3725 4710);
DISPLAY 0.617021 (-3725 4710);
PAINT ORANGE (-3725 4710);
WIRE 17 -1 (-3250 4025)(-3250 4075);
WIRE 17 -1 (-3250 4075)(-3250 4125);
WIRE 17 -1 (-3250 4675)(-3250 4700);
WIRE 17 -1 (-3250 4625)(-3250 4675);
WIRE 17 -1 (-3250 4125)(-3250 4175);
WIRE 17 -1 (-3250 4175)(-3250 4225);
WIRE 17 -1 (-3250 4575)(-3250 4625);
WIRE 17 -1 (-3250 4525)(-3250 4575);
WIRE 17 -1 (-3250 4225)(-3250 4275);
WIRE 17 -1 (-3250 4275)(-3250 4325);
WIRE 17 -1 (-3250 4475)(-3250 4525);
WIRE 17 -1 (-3250 4425)(-3250 4475);
WIRE 17 -1 (-3250 4325)(-3250 4375);
WIRE 17 -1 (-3250 4375)(-3250 4425);
WIRE 17 -1 (-3800 3500)(-4250 3500);
FORCEPROP 2 LAST SIG_NAME M_C_CLK_DN<3:0>
J 0
(-4225 3510);
DISPLAY 0.617021 (-4225 3510);
PAINT ORANGE (-4225 3510);
WIRE 17 -1 (-3800 3325)(-3800 3425);
WIRE 17 -1 (-3800 3425)(-3800 3500);
WIRE 17 -1 (-3650 3550)(-4250 3550);
FORCEPROP 2 LAST SIG_NAME M_C_CLK_DP<3:0>
J 0
(-4225 3560);
DISPLAY 0.617021 (-4225 3560);
PAINT ORANGE (-4225 3560);
WIRE 17 -1 (-3650 3550)(-3650 3475);
WIRE 17 -1 (-3650 3475)(-3650 3375);
WIRE 17 -1 (-3250 3750)(-3750 3750);
FORCEPROP 2 LAST SIG_NAME M_C_BA<1:0>
J 0
(-3725 3760);
DISPLAY 0.617021 (-3725 3760);
PAINT ORANGE (-3725 3760);
WIRE 17 -1 (-3250 3750)(-3250 3725);
WIRE 17 -1 (-3250 3675)(-3250 3725);
WIRE 17 -1 (-3250 3025)(-3250 3075);
WIRE 17 -1 (-3250 3075)(-3250 3125);
WIRE 17 -1 (-3250 3200)(-3750 3200);
FORCEPROP 2 LAST SIG_NAME M_C_CS_N<7:0>
J 0
(-3725 3210);
DISPLAY 0.617021 (-3725 3210);
PAINT ORANGE (-3725 3210);
WIRE 17 -1 (-3250 3125)(-3250 3175);
WIRE 17 -1 (-3250 3175)(-3250 3200);
WIRE 17 -1 (-3250 2275)(-3250 2325);
WIRE 17 -1 (-3250 2325)(-3250 2375);
WIRE 17 -1 (-3250 2375)(-3250 2425);
WIRE 17 -1 (-3250 2425)(-3250 2475);
WIRE 17 -1 (-3250 2475)(-3250 2525);
WIRE 17 -1 (-3250 2650)(-3750 2650);
FORCEPROP 2 LAST SIG_NAME M_C_ECC<7:0>
J 0
(-3700 2660);
DISPLAY 0.617021 (-3700 2660);
PAINT ORANGE (-3700 2660);
WIRE 17 -1 (-3250 2625)(-3250 2650);
WIRE 17 -1 (-3250 2525)(-3250 2575);
WIRE 17 -1 (-3250 2575)(-3250 2625);
WIRE 17 -1 (-3250 2950)(-3750 2950);
FORCEPROP 2 LAST SIG_NAME M_C_CKE<3:0>
J 0
(-3700 2960);
DISPLAY 0.617021 (-3700 2960);
PAINT ORANGE (-3700 2960);
WIRE 17 -1 (-3250 2875)(-3250 2925);
WIRE 17 -1 (-3250 2925)(-3250 2950);
WIRE 17 -1 (-3250 3650)(-3750 3650);
FORCEPROP 2 LAST SIG_NAME M_C_BG<1:0>
J 0
(-3725 3660);
DISPLAY 0.617021 (-3725 3660);
PAINT ORANGE (-3725 3660);
WIRE 17 -1 (-3250 3625)(-3250 3650);
WIRE 17 -1 (-3250 3575)(-3250 3625);
WIRE 17 -1 (-3250 2850)(-3750 2850);
FORCEPROP 2 LAST SIG_NAME M_C_ODT<3:0>
J 0
(-3700 2860);
DISPLAY 0.617021 (-3700 2860);
PAINT ORANGE (-3700 2860);
WIRE 17 -1 (-3250 2775)(-3250 2850);
WIRE 17 -1 (-3250 2725)(-3250 2775);
WIRE 16 -1 (-1750 4350)(-1950 4350);
WIRE 16 -1 (-2950 4450)(-3150 4450);
WIRE 16 -1 (-2950 4150)(-3150 4150);
WIRE 16 -1 (-2950 4100)(-3150 4100);
WIRE 16 -1 (850 4750)(450 4750);
WIRE 16 -1 (-4750 1500)(-4650 1500);
WIRE 16 -1 (-2950 1500)(-4650 1500);
FORCEPROP 2 LAST SIG_NAME M_C_VREF
J 0
(-3700 1510);
DISPLAY 0.617021 (-3700 1510);
PAINT ORANGE (-3700 1510);
WIRE 16 -1 (-4650 1400)(-4650 1500);
WIRE 16 -1 (-3800 1350)(-2950 1350);
FORCEPROP 2 LAST SIG_NAME TP_CH_C_DIMM_C0_RFU_1
J 0
(-3750 1360);
DISPLAY 0.617021 (-3750 1360);
PAINT ORANGE (-3750 1360);
FORCEPROP 2 LASTPROP $XRERR UNIQUE?
J 0
(-4040 1350);
DISPLAY 0.638298 (-4040 1350);
PAINT MONO (-4040 1350);
DISPLAY INVISIBLE (-4040 1350);
WIRE 16 -1 (-3800 1300)(-2950 1300);
FORCEPROP 2 LAST SIG_NAME TP_CH_C_DIMM_C0_RFU_0
J 0
(-3750 1310);
DISPLAY 0.617021 (-3750 1310);
PAINT ORANGE (-3750 1310);
FORCEPROP 2 LASTPROP $XRERR UNIQUE?
J 0
(-4040 1300);
DISPLAY 0.638298 (-4040 1300);
PAINT MONO (-4040 1300);
DISPLAY INVISIBLE (-4040 1300);
WIRE 16 -1 (-3800 1400)(-2950 1400);
FORCEPROP 2 LAST SIG_NAME TP_CH_C_DIMM_C0_RFU_2
J 0
(-3750 1410);
DISPLAY 0.617021 (-3750 1410);
PAINT ORANGE (-3750 1410);
FORCEPROP 2 LASTPROP $XRERR UNIQUE?
J 0
(-4040 1400);
DISPLAY 0.638298 (-4040 1400);
PAINT MONO (-4040 1400);
DISPLAY INVISIBLE (-4040 1400);
WIRE 16 -1 (-2950 2000)(-3975 2000);
FORCEPROP 2 LAST SIG_NAME M_C_ALERT_N
J 0
(-3925 2010);
DISPLAY 0.617021 (-3925 2010);
PAINT ORANGE (-3925 2010);
WIRE 16 -1 (-2950 1950)(-3950 1950);
FORCEPROP 2 LAST SIG_NAME M_C_ACT_N
J 0
(-3900 1960);
DISPLAY 0.617021 (-3900 1960);
PAINT ORANGE (-3900 1960);
WIRE 16 -1 (-3750 1600)(-2950 1600);
FORCEPROP 2 LAST SIG_NAME SMB_DDR_ABC_VPP_SCL
J 0
(-3710 1610);
DISPLAY 0.617021 (-3710 1610);
PAINT ORANGE (-3710 1610);
WIRE 16 -1 (-2950 1650)(-3750 1650);
WIRE 16 -1 (-3800 1200)(-2950 1200);
FORCEPROP 2 LAST SIG_NAME FM_ADR_COMPLETE_ABC_N
J 0
(-3750 1210);
DISPLAY 0.617021 (-3750 1210);
PAINT ORANGE (-3750 1210);
WIRE 16 -1 (-3400 2300)(-4125 2300);
FORCEPROP 2 LAST SIG_NAME FM_DIMM_EVENT_COD_N
J 0
(-4105 2319);
DISPLAY 0.617021 (-4105 2319);
PAINT ORANGE (-4105 2319);
WIRE 16 -1 (-3400 2050)(-3400 2300);
WIRE 16 -1 (-3400 2050)(-2950 2050);
WIRE 16 -1 (-3350 2550)(-3750 2550);
FORCEPROP 2 LAST SIG_NAME M_ABC_RST_N
J 0
(-3700 2560);
DISPLAY 0.617021 (-3700 2560);
PAINT ORANGE (-3700 2560);
WIRE 16 -1 (-3350 2100)(-3350 2550);
WIRE 16 -1 (-2950 2100)(-3350 2100);
WIRE 16 -1 (-3300 2600)(-3750 2600);
FORCEPROP 2 LAST SIG_NAME M_C_PAR
J 0
(-3700 2610);
DISPLAY 0.617021 (-3700 2610);
PAINT ORANGE (-3700 2610);
WIRE 16 -1 (-3300 2150)(-3300 2600);
WIRE 16 -1 (-2950 2150)(-3300 2150);
WIRE 16 -1 (-3150 3250)(-3750 3250);
FORCEPROP 2 LAST SIG_NAME M_C_C<2>
J 0
(-3725 3260);
DISPLAY 0.617021 (-3725 3260);
PAINT ORANGE (-3725 3260);
WIRE 16 -1 (-3150 3250)(-3150 3200);
WIRE 16 -1 (-3150 3200)(-2950 3200);
WIRE 16 -1 (-2950 3000)(-3150 3000);
WIRE 16 -1 (-2950 2850)(-3150 2850);
WIRE 16 -1 (-2950 2750)(-3150 2750);
WIRE 16 -1 (-2950 2700)(-3150 2700);
WIRE 16 -1 (-2950 2600)(-3150 2600);
WIRE 16 -1 (-2950 3900)(-3150 3900);
WIRE 16 -1 (-2950 3650)(-3150 3650);
WIRE 16 -1 (-2950 3600)(-3150 3600);
WIRE 16 -1 (-2950 3550)(-3150 3550);
WIRE 16 -1 (-2950 2900)(-3150 2900);
WIRE 16 -1 (-2950 2250)(-3150 2250);
WIRE 16 -1 (-2950 2300)(-3150 2300);
WIRE 16 -1 (-2950 2350)(-3150 2350);
WIRE 16 -1 (-2950 2400)(-3150 2400);
WIRE 16 -1 (-2950 2450)(-3150 2450);
WIRE 16 -1 (-2950 2500)(-3150 2500);
WIRE 16 -1 (-2950 2550)(-3150 2550);
WIRE 16 -1 (-2950 4050)(-3150 4050);
WIRE 16 -1 (-2950 4000)(-3150 4000);
WIRE 16 -1 (-2950 3950)(-3150 3950);
WIRE 16 -1 (-2950 3850)(-3150 3850);
WIRE 16 -1 (-2950 3800)(-3150 3800);
WIRE 16 -1 (-2950 3050)(-3150 3050);
WIRE 16 -1 (-2950 3100)(-3150 3100);
WIRE 16 -1 (-2950 3150)(-3150 3150);
WIRE 16 -1 (-2950 3700)(-3150 3700);
WIRE 16 -1 (-2950 3450)(-3550 3450);
WIRE 16 -1 (-2950 3300)(-3700 3300);
WIRE 16 -1 (-2950 3350)(-3550 3350);
WIRE 16 -1 (-2950 3400)(-3700 3400);
WIRE 16 -1 (-1750 1500)(-1950 1500);
WIRE 16 -1 (-1750 1750)(-1950 1750);
WIRE 16 -1 (-1750 1700)(-1950 1700);
WIRE 16 -1 (-1750 1650)(-1950 1650);
WIRE 16 -1 (-1750 1600)(-1950 1600);
WIRE 16 -1 (-1750 1550)(-1950 1550);
WIRE 16 -1 (-1750 1800)(-1950 1800);
WIRE 16 -1 (-1750 1850)(-1950 1850);
WIRE 16 -1 (-1750 1900)(-1950 1900);
WIRE 16 -1 (-1750 1950)(-1950 1950);
WIRE 16 -1 (-1750 2000)(-1950 2000);
WIRE 16 -1 (-1750 2350)(-1950 2350);
WIRE 16 -1 (-1750 2250)(-1950 2250);
WIRE 16 -1 (-1750 2050)(-1950 2050);
WIRE 16 -1 (-1750 2100)(-1950 2100);
WIRE 16 -1 (-1750 2150)(-1950 2150);
WIRE 16 -1 (-1750 2200)(-1950 2200);
WIRE 16 -1 (-1750 2300)(-1950 2300);
WIRE 16 -1 (-1750 2400)(-1950 2400);
WIRE 16 -1 (-1750 2450)(-1950 2450);
WIRE 16 -1 (-1750 2500)(-1950 2500);
WIRE 16 -1 (-1750 2550)(-1950 2550);
WIRE 16 -1 (-1750 2800)(-1950 2800);
WIRE 16 -1 (-1750 2850)(-1950 2850);
WIRE 16 -1 (-1750 2600)(-1950 2600);
WIRE 16 -1 (-1750 2650)(-1950 2650);
WIRE 16 -1 (-1750 2700)(-1950 2700);
WIRE 16 -1 (-1750 2750)(-1950 2750);
WIRE 16 -1 (-1750 3000)(-1950 3000);
WIRE 16 -1 (-1750 3050)(-1950 3050);
WIRE 16 -1 (-1750 2900)(-1950 2900);
WIRE 16 -1 (-1750 2950)(-1950 2950);
WIRE 16 -1 (-1750 3400)(-1950 3400);
WIRE 16 -1 (-1750 3300)(-1950 3300);
WIRE 16 -1 (-1750 3250)(-1950 3250);
WIRE 16 -1 (-1750 3100)(-1950 3100);
WIRE 16 -1 (-1750 3150)(-1950 3150);
WIRE 16 -1 (-1750 3200)(-1950 3200);
WIRE 16 -1 (-1750 3350)(-1950 3350);
WIRE 16 -1 (-1750 3450)(-1950 3450);
WIRE 16 -1 (-1750 3500)(-1950 3500);
WIRE 16 -1 (-1750 3550)(-1950 3550);
WIRE 16 -1 (-1750 3850)(-1950 3850);
WIRE 16 -1 (-1750 3900)(-1950 3900);
WIRE 16 -1 (-1750 3950)(-1950 3950);
WIRE 16 -1 (-1750 4000)(-1950 4000);
WIRE 16 -1 (-1750 4050)(-1950 4050);
WIRE 16 -1 (-1750 3600)(-1950 3600);
WIRE 16 -1 (-1750 3650)(-1950 3650);
WIRE 16 -1 (-1750 3700)(-1950 3700);
WIRE 16 -1 (-1750 3750)(-1950 3750);
WIRE 16 -1 (-1750 3800)(-1950 3800);
WIRE 16 -1 (-2950 4600)(-3150 4600);
WIRE 16 -1 (-2950 4550)(-3150 4550);
WIRE 16 -1 (-2950 4500)(-3150 4500);
WIRE 16 -1 (-2950 4350)(-3150 4350);
WIRE 16 -1 (-2950 4300)(-3150 4300);
WIRE 16 -1 (-2950 4250)(-3150 4250);
WIRE 16 -1 (-2950 4200)(-3150 4200);
WIRE 16 -1 (-2950 4650)(-3150 4650);
WIRE 16 -1 (-2950 4400)(-3150 4400);
WIRE 16 -1 (-1750 4600)(-1950 4600);
WIRE 16 -1 (-1750 4550)(-1950 4550);
WIRE 16 -1 (-1750 4100)(-1950 4100);
WIRE 16 -1 (-1750 4150)(-1950 4150);
WIRE 16 -1 (-1750 4200)(-1950 4200);
WIRE 16 -1 (-1750 4400)(-1950 4400);
WIRE 16 -1 (-1750 4250)(-1950 4250);
WIRE 16 -1 (-1750 4300)(-1950 4300);
WIRE 16 -1 (-1750 4450)(-1950 4450);
WIRE 16 -1 (-1750 4500)(-1950 4500);
WIRE 16 -1 (-1750 4650)(-1950 4650);
WIRE 16 -1 (850 4050)(450 4050);
WIRE 16 -1 (650 4000)(450 4000);
WIRE 16 -1 (850 3950)(450 3950);
WIRE 16 -1 (650 3900)(450 3900);
WIRE 16 -1 (850 3850)(450 3850);
WIRE 16 -1 (650 3800)(450 3800);
WIRE 16 -1 (850 3750)(450 3750);
WIRE 16 -1 (650 3700)(450 3700);
WIRE 16 -1 (850 3650)(450 3650);
WIRE 16 -1 (650 3600)(450 3600);
WIRE 16 -1 (850 3550)(450 3550);
WIRE 16 -1 (650 3500)(450 3500);
WIRE 16 -1 (850 3450)(450 3450);
WIRE 16 -1 (650 4400)(450 4400);
WIRE 16 -1 (850 4350)(450 4350);
WIRE 16 -1 (650 4300)(450 4300);
WIRE 16 -1 (850 4250)(450 4250);
WIRE 16 -1 (650 4200)(450 4200);
WIRE 16 -1 (850 4150)(450 4150);
WIRE 16 -1 (650 4100)(450 4100);
WIRE 16 -1 (650 5100)(450 5100);
WIRE 16 -1 (850 5050)(450 5050);
WIRE 16 -1 (650 5000)(450 5000);
WIRE 16 -1 (850 4950)(450 4950);
WIRE 16 -1 (650 4900)(450 4900);
WIRE 16 -1 (850 4850)(450 4850);
WIRE 16 -1 (650 4800)(450 4800);
WIRE 16 -1 (650 4700)(450 4700);
WIRE 16 -1 (850 4650)(450 4650);
WIRE 16 -1 (650 4600)(450 4600);
WIRE 16 -1 (850 4550)(450 4550);
WIRE 16 -1 (650 4500)(450 4500);
WIRE 16 -1 (850 4450)(450 4450);
WIRE 16 -1 (650 5200)(450 5200);
WIRE 16 -1 (850 5150)(450 5150);
DOT 1 (1100 2500);
DOT 1 (2500 3500);
DOT 1 (2500 3550);
DOT 1 (700 2900);
DOT 1 (-700 2450);
DOT 1 (-700 1250);
DOT 1 (-700 2550);
DOT 1 (-700 1300);
DOT 1 (-700 1450);
DOT 1 (-700 1400);
DOT 1 (-700 1350);
DOT 1 (-700 1500);
DOT 1 (-700 1550);
DOT 1 (-700 1600);
DOT 1 (-700 1650);
DOT 1 (-700 1700);
DOT 1 (-700 1750);
DOT 1 (-700 1800);
DOT 1 (-700 1900);
DOT 1 (-700 2050);
DOT 1 (-700 2100);
DOT 1 (-700 2200);
DOT 1 (-700 2150);
DOT 1 (-700 2350);
DOT 1 (-700 2250);
DOT 1 (-700 2300);
DOT 1 (-700 2400);
DOT 1 (-700 2850);
DOT 1 (-700 2800);
DOT 1 (-700 2900);
DOT 1 (1100 1500);
DOT 1 (1100 1550);
DOT 1 (1100 1600);
DOT 1 (1100 1650);
DOT 1 (1100 1700);
DOT 1 (1100 1750);
DOT 1 (1100 1800);
DOT 1 (1100 1850);
DOT 1 (1100 1900);
DOT 1 (1100 1950);
DOT 1 (1100 2000);
DOT 1 (1100 2050);
DOT 1 (1100 2150);
DOT 1 (1100 2200);
DOT 1 (1100 2250);
DOT 1 (1100 2300);
DOT 1 (1100 2350);
DOT 1 (1100 2400);
DOT 1 (1100 2450);
DOT 1 (1100 2550);
DOT 1 (1100 2600);
DOT 1 (1100 2650);
DOT 1 (1100 2700);
DOT 1 (1100 2850);
DOT 1 (1100 2900);
DOT 1 (1100 2950);
DOT 1 (1100 3000);
DOT 1 (1100 3050);
DOT 1 (1100 3100);
DOT 1 (1100 3150);
DOT 1 (1100 3200);
DOT 1 (1100 3250);
DOT 1 (1100 3300);
DOT 1 (1100 3350);
DOT 1 (1100 3400);
DOT 1 (1100 3450);
DOT 1 (1100 3500);
DOT 1 (1100 3550);
DOT 1 (1100 3600);
DOT 1 (1100 3650);
DOT 1 (1100 3700);
DOT 1 (2500 1500);
DOT 1 (2500 1550);
DOT 1 (2500 1600);
DOT 1 (2500 1650);
DOT 1 (2500 1700);
DOT 1 (2500 1750);
DOT 1 (2500 1800);
DOT 1 (2500 1850);
DOT 1 (2500 1900);
DOT 1 (2500 1950);
DOT 1 (2500 2000);
DOT 1 (2500 2050);
DOT 1 (2500 2100);
DOT 1 (2500 2150);
DOT 1 (2500 2200);
DOT 1 (2500 2300);
DOT 1 (2500 2250);
DOT 1 (2500 2350);
DOT 1 (2500 2400);
DOT 1 (2500 2500);
DOT 1 (2500 2550);
DOT 1 (2500 2600);
DOT 1 (2500 2650);
DOT 1 (2500 2700);
DOT 1 (2500 2750);
DOT 1 (2500 2800);
DOT 1 (2500 2850);
DOT 1 (2500 2900);
DOT 1 (2500 3000);
DOT 1 (2500 3050);
DOT 1 (2500 3100);
DOT 1 (2500 3150);
DOT 1 (2500 3200);
DOT 1 (2500 3250);
DOT 1 (2500 3300);
DOT 1 (2500 3350);
DOT 1 (2500 3450);
DOT 1 (2500 3600);
DOT 1 (2500 3650);
DOT 1 (2500 3700);
DOT 1 (1100 3750);
DOT 1 (2500 3750);
DOT 1 (1100 2800);
DOT 1 (-4650 1500);
DOT 1 (-700 2750);
DOT 1 (2500 3400);
DOT 1 (1100 2750);
DOT 1 (2500 2450);
DOT 1 (1100 2100);
DOT 1 (-700 1850);
DOT 1 (-3300 1750);
DOT 1 (-3300 1850);
DOT 1 (-700 2000);
DOT 1 (-700 1950);
DOT 1 (2500 2950);
FORCENOTE
PVDDQ (SINGLE SIDE) CAP: 10UF X1, 22UF X50
(-3950 5100) 0;
DISPLAY LEFT (-3950 5100);
DISPLAY 1.021277 (-3950 5100);
PAINT PURPLE (-3950 5100);
FORCENOTE
PVTT CAP: 100UF X2, 47UF X1
(-3950 5150) 0;
DISPLAY LEFT (-3950 5150);
DISPLAY 1.021277 (-3950 5150);
PAINT PURPLE (-3950 5150);
FORCENOTE
PVPP CAP: 10UF X12
(-3950 5200) 0;
DISPLAY LEFT (-3950 5200);
DISPLAY 1.021277 (-3950 5200);
PAINT PURPLE (-3950 5200);
FORCENOTE
PVDDQ (DOUBLE SIDE) CAP: 100UF X8, 47UF X41
(-3950 5050) 0;
DISPLAY LEFT (-3950 5050);
DISPLAY 1.021277 (-3950 5050);
PAINT PURPLE (-3950 5050);
FORCENOTE
PLACE CAP NEAR DIMM CONNECTOR
(-5301 948) 0;
DISPLAY LEFT (-5301 948);
DISPLAY 1.595745 (-5301 948);
PAINT PURPLE (-5301 948);
FORCENOTE
SMBUS ADDR: 0XA8
(-5267 687) 0;
DISPLAY LEFT (-5267 687);
DISPLAY 1.574468 (-5267 687);
PAINT PURPLE (-5267 687);
FORCENOTE
CAP BETWEEN DIMM
(-3950 5275) 0;
DISPLAY LEFT (-3950 5275);
DISPLAY 1.276596 (-3950 5275);
PAINT PURPLE (-3950 5275);
QUIT
